FILE_TYPE = MACRO_DRAWING;
SET COLOR_WIRE YELLOW;
SET COLOR_PROP ORANGE;
SET COLOR_DOT WHITE;
SET COLOR_ARC YELLOW;
SET COLOR_BODY GREEN;
SET COLOR_NOTE PURPLE;
SET PROP_DISPLAY VALUE;
SET PAGE_NUMBER P237;
FORCEADD OFFPAGE..1
(-1150 6475);
PAINT AQUA (-1150 6475);
FORCEPROP 2 LAST $XR0 164 
J 0
(-1402 6475);
DISPLAY 0.638298 (-1402 6475);
PAINT MONO (-1402 6475);
FORCEPROP 2 LAST $XR1 162 
J 0
(-1522 6475);
DISPLAY 0.638298 (-1522 6475);
PAINT MONO (-1522 6475);
FORCEPROP 2 LAST $XR2 163 
J 0
(-1642 6475);
DISPLAY 0.638298 (-1642 6475);
PAINT MONO (-1642 6475);
FORCEPROP 2 LAST $XR3 238 
J 0
(-1762 6475);
DISPLAY 0.638298 (-1762 6475);
PAINT MONO (-1762 6475);
FORCEPROP 1 LAST COMMENT_BODY TRUE
J 0
(-1025 6375);
DISPLAY 0.872340 (-1025 6375);
PAINT GREEN (-1025 6375);
DISPLAY INVISIBLE (-1025 6375);
FORCEPROP 1 LAST OFFPAGE TRUE
J 0
(-825 6350);
DISPLAY 0.872340 (-825 6350);
PAINT AQUA (-825 6350);
DISPLAY INVISIBLE (-825 6350);
FORCEPROP 2 LAST CDS_LIB standard
J 0
(-1150 6475);
DISPLAY INVISIBLE (-1150 6475);
FORCEPROP 2 LAST PATH I33
J 0
(-1400 6525);
DISPLAY 1.021277 (-1400 6525);
DISPLAY INVISIBLE (-1400 6525);
FORCEADD UNIVERSAL_GND..1
(-250 5875);
FORCEPROP 3 LASTPIN (-250 5925) SIG_NAME GND\g
J 0
(-240 5935);
DISPLAY 0.659574 (-240 5935);
PAINT MONO (-240 5935);
DISPLAY INVISIBLE (-240 5935);
FORCEPROP 1 LAST HDL_POWER GND
J 1
(-225 5800);
DISPLAY 0.872340 (-225 5800);
PAINT GREEN (-225 5800);
DISPLAY INVISIBLE (-225 5800);
FORCEPROP 2 LAST CDS_LIB logical_power
J 0
(-250 5875);
DISPLAY INVISIBLE (-250 5875);
FORCEPROP 1 LAST PATH I34
J 0
(-175 5875);
DISPLAY 0.872340 (-175 5875);
PAINT AQUA (-175 5875);
DISPLAY INVISIBLE (-175 5875);
FORCEADD Q_CAP..1
(-250 6175);
FORCEPROP 1 LAST PART_NUMBER CH0396J0B04
J 0
(-200 6025);
DISPLAY 0.574468 (-200 6025);
PAINT WHITE (-200 6025);
DISPLAY INVISIBLE (-200 6025);
FORCEPROP 2 LAST ROOM NIC1_P3V3_BOM2
J 0
(-225 6300);
DISPLAY 0.319149 (-225 6300);
FORCEPROP 1 LAST VOLTAGE 50V
J 0
(-200 6125);
DISPLAY 0.574468 (-200 6125);
PAINT SKYBLUE (-200 6125);
FORCEPROP 1 LAST PACK_TYPE C0402
J 0
(-200 6075);
DISPLAY 0.574468 (-200 6075);
PAINT SKYBLUE (-200 6075);
FORCEPROP 1 LAST VALUE 39PF
J 0
(-200 6200);
DISPLAY 0.574468 (-200 6200);
PAINT SKYBLUE (-200 6200);
FORCEPROP 1 LAST MATERIAL EMPTY
J 0
(-200 6150);
DISPLAY 0.574468 (-200 6150);
PAINT RED (-200 6150);
FORCEPROP 1 LAST LOCATION PC2168
J 0
(-200 6250);
DISPLAY 0.723404 (-200 6250);
PAINT AQUA (-200 6250);
FORCEPROP 1 LAST PATH I35
J 0
(-200 6325);
DISPLAY 0.978723 (-200 6325);
PAINT WHITE (-200 6325);
DISPLAY INVISIBLE (-200 6325);
FORCEPROP 1 LAST TOLERANCE 5%
J 0
(-200 6125);
DISPLAY 0.723404 (-200 6125);
PAINT SKYBLUE (-200 6125);
DISPLAY INVISIBLE (-200 6125);
FORCEPROP 2 LAST CDS_LIB pure_quanta
J 0
(-250 6175);
DISPLAY INVISIBLE (-250 6175);
FORCEPROP 0 LAST $SEC 1
J 0
(-200 6300);
DISPLAY INVISIBLE (-200 6300);
FORCEPROP 0 LAST CDS_SEC 1
J 0
(-200 6300);
DISPLAY INVISIBLE (-200 6300);
FORCEPROP 1 LASTPIN (-250 6275) $PN 1
J 0
(-240 6255);
DISPLAY 0.787234 (-240 6255);
PAINT MONO (-240 6255);
DISPLAY INVISIBLE (-240 6255);
FORCEPROP 1 LASTPIN (-250 6075) $PN 2
J 0
(-240 6055);
DISPLAY 0.787234 (-240 6055);
PAINT MONO (-240 6055);
DISPLAY INVISIBLE (-240 6055);
FORCEADD Q_RES..2
(150 6175);
FORCEPROP 1 LAST PART_NUMBER CS37152FB05
J 0
(155 6017);
DISPLAY 0.595745 (155 6017);
PAINT WHITE (155 6017);
DISPLAY INVISIBLE (155 6017);
FORCEPROP 2 LAST ROOM NIC1_P3V3_BOM2
J 0
(175 6300);
DISPLAY 0.319149 (175 6300);
FORCEPROP 1 LAST MATERIAL EMPTY
J 0
(175 6050);
DISPLAY 0.723404 (175 6050);
PAINT RED (175 6050);
FORCEPROP 1 LAST PACK_TYPE 0402LF
J 0
(175 6100);
DISPLAY 0.574468 (175 6100);
PAINT SKYBLUE (175 6100);
FORCEPROP 1 LAST VALUE 71.5K
J 0
(175 6200);
DISPLAY 0.574468 (175 6200);
PAINT SKYBLUE (175 6200);
FORCEPROP 1 LAST TOLERANCE 1%
J 0
(175 6150);
DISPLAY 0.574468 (175 6150);
PAINT SKYBLUE (175 6150);
FORCEPROP 1 LAST LOCATION PR3855
J 0
(175 6250);
DISPLAY 0.723404 (175 6250);
PAINT AQUA (175 6250);
FORCEPROP 1 LAST PATH I43
J 0
(200 6350);
DISPLAY 0.978723 (200 6350);
PAINT WHITE (200 6350);
DISPLAY INVISIBLE (200 6350);
FORCEPROP 1 LAST WATTAGE 1/16W
J 0
(175 6150);
DISPLAY 0.723404 (175 6150);
PAINT SKYBLUE (175 6150);
DISPLAY INVISIBLE (175 6150);
FORCEPROP 2 LAST CDS_LIB pure_quanta
J 0
(150 6175);
DISPLAY INVISIBLE (150 6175);
FORCEPROP 0 LAST $SEC 1
J 0
(175 6300);
DISPLAY INVISIBLE (175 6300);
FORCEPROP 0 LAST CDS_SEC 1
J 0
(175 6300);
DISPLAY INVISIBLE (175 6300);
FORCEPROP 1 LASTPIN (150 6275) $PN 1
J 0
(155 6237);
DISPLAY 0.787234 (155 6237);
PAINT MONO (155 6237);
DISPLAY INVISIBLE (155 6237);
FORCEPROP 1 LASTPIN (150 6075) $PN 2
J 0
(155 6085);
DISPLAY 0.787234 (155 6085);
PAINT MONO (155 6085);
DISPLAY INVISIBLE (155 6085);
FORCEADD Q_RES..1
(225 6475);
FORCEPROP 1 LAST PART_NUMBER CS00002JB13
J 0
(150 6425);
DISPLAY 0.510638 (150 6425);
DISPLAY INVISIBLE (150 6425);
FORCEPROP 2 LAST ROOM NIC1_P3V3_BOM2
J 0
(-75 6525);
DISPLAY 0.510638 (-75 6525);
FORCEPROP 1 LAST TOLERANCE 5%
J 0
(400 6475);
DISPLAY 0.510638 (400 6475);
FORCEPROP 1 LAST VALUE 0
J 2
(375 6475);
DISPLAY 0.510638 (375 6475);
FORCEPROP 1 LAST PACK_TYPE 0402LF
J 0
(475 6475);
DISPLAY 0.510638 (475 6475);
FORCEPROP 1 LAST WATTAGE 1/16W
J 2
(400 6400);
DISPLAY 0.510638 (400 6400);
FORCEPROP 1 LAST MATERIAL EMPTY
J 0
(150 6400);
DISPLAY 0.510638 (150 6400);
PAINT RED (150 6400);
FORCEPROP 1 LAST $LOCATION R3631
J 0
(-25 6475);
DISPLAY 0.638298 (-25 6475);
FORCEPROP 1 LASTPIN (125 6475) $PN 1
J 0
(137 6487);
DISPLAY 0.787234 (137 6487);
PAINT MONO (137 6487);
FORCEPROP 1 LASTPIN (325 6475) $PN 2
J 0
(287 6487);
DISPLAY 0.787234 (287 6487);
PAINT MONO (287 6487);
FORCEPROP 1 LAST PATH I44
J 0
(175 6625);
DISPLAY 0.978723 (175 6625);
PAINT WHITE (175 6625);
DISPLAY INVISIBLE (175 6625);
FORCEPROP 2 LAST CDS_LIB pure_quanta
J 0
(225 6475);
DISPLAY INVISIBLE (225 6475);
FORCEPROP 0 LAST CDS_LOCATION R3631
J 0
(175 6575);
DISPLAY 1.021277 (175 6575);
DISPLAY INVISIBLE (175 6575);
FORCEPROP 0 LAST $SEC 1
J 0
(175 6575);
DISPLAY 0.680851 (175 6575);
PAINT MONO (175 6575);
DISPLAY INVISIBLE (175 6575);
FORCEPROP 0 LAST CDS_SEC 1
J 0
(175 6575);
DISPLAY 1.021277 (175 6575);
DISPLAY INVISIBLE (175 6575);
FORCEADD UNIVERSAL_GND..1
(495 5883);
FORCEPROP 3 LASTPIN (495 5933) SIG_NAME GND\g
J 0
(505 5943);
DISPLAY 0.659574 (505 5943);
PAINT MONO (505 5943);
DISPLAY INVISIBLE (505 5943);
FORCEPROP 1 LAST HDL_POWER GND
J 1
(520 5808);
DISPLAY 0.872340 (520 5808);
PAINT GREEN (520 5808);
DISPLAY INVISIBLE (520 5808);
FORCEPROP 2 LAST CDS_LIB logical_power
J 0
(495 5883);
DISPLAY INVISIBLE (495 5883);
FORCEPROP 1 LAST PATH I45
J 0
(570 5883);
DISPLAY 0.872340 (570 5883);
PAINT AQUA (570 5883);
DISPLAY INVISIBLE (570 5883);
FORCEADD Q_RES..1
R 1
(495 6158);
FORCEPROP 1 LAST PART_NUMBER CS21332FB05
J 0
(525 6025);
DISPLAY 0.638298 (525 6025);
DISPLAY INVISIBLE (525 6025);
FORCEPROP 2 LAST ROOM NIC1_P3V3_BOM2
J 0
(525 6275);
DISPLAY 0.255319 (525 6275);
FORCEPROP 1 LAST MATERIAL EMPTY
J 0
(525 5950);
DISPLAY 0.787234 (525 5950);
PAINT RED (525 5950);
FORCEPROP 1 LAST VALUE 1.33K
J 0
(525 6175);
DISPLAY 0.638298 (525 6175);
FORCEPROP 1 LAST PACK_TYPE 0402LF
J 0
(525 6075);
DISPLAY 0.638298 (525 6075);
FORCEPROP 1 LAST TOLERANCE 1%
J 0
(525 6125);
DISPLAY 0.638298 (525 6125);
FORCEPROP 1 LAST LOCATION PR3856
J 0
(525 6225);
DISPLAY 0.638298 (525 6225);
FORCEPROP 1 LAST PATH I46
R 1
J 0
(345 6108);
DISPLAY 0.978723 (345 6108);
PAINT WHITE (345 6108);
DISPLAY INVISIBLE (345 6108);
FORCEPROP 1 LAST WATTAGE 1/16W
R 1
J 2
(645 6133);
DISPLAY 0.978723 (645 6133);
DISPLAY INVISIBLE (645 6133);
FORCEPROP 2 LAST CDS_LIB pure_quanta
J 0
(495 6158);
DISPLAY INVISIBLE (495 6158);
FORCEPROP 0 LAST $SEC 1
R 1
J 0
(520 6233);
DISPLAY INVISIBLE (520 6233);
FORCEPROP 0 LAST CDS_SEC 1
R 1
J 0
(520 6233);
DISPLAY INVISIBLE (520 6233);
FORCEPROP 1 LASTPIN (495 6058) $PN 1
R 1
J 0
(483 6070);
DISPLAY 0.787234 (483 6070);
PAINT MONO (483 6070);
DISPLAY INVISIBLE (483 6070);
FORCEPROP 1 LASTPIN (495 6258) $PN 2
R 1
J 0
(483 6220);
DISPLAY 0.787234 (483 6220);
PAINT MONO (483 6220);
DISPLAY INVISIBLE (483 6220);
FORCEADD UNIVERSAL_GND..1
(470 6533);
FORCEPROP 3 LASTPIN (470 6583) SIG_NAME GND\g
J 0
(480 6593);
DISPLAY 0.659574 (480 6593);
PAINT MONO (480 6593);
DISPLAY INVISIBLE (480 6593);
FORCEPROP 1 LAST HDL_POWER GND
J 1
(495 6458);
DISPLAY 0.872340 (495 6458);
PAINT GREEN (495 6458);
DISPLAY INVISIBLE (495 6458);
FORCEPROP 2 LAST CDS_LIB logical_power
J 0
(470 6533);
DISPLAY INVISIBLE (470 6533);
FORCEPROP 1 LAST PATH I47
J 0
(545 6533);
DISPLAY 0.872340 (545 6533);
PAINT AQUA (545 6533);
DISPLAY INVISIBLE (545 6533);
FORCEADD Q_CAP..1
(470 6758);
FORCEPROP 1 LAST PART_NUMBER CH5104KEB02
J 0
(520 6608);
DISPLAY 0.978723 (520 6608);
DISPLAY INVISIBLE (520 6608);
FORCEPROP 2 LAST ROOM NIC1_P3V3_BOM2
J 0
(525 6925);
DISPLAY 0.510638 (525 6925);
FORCEPROP 1 LAST VALUE 1UF
J 0
(520 6808);
DISPLAY 0.978723 (520 6808);
FORCEPROP 1 LAST TOLERANCE 10%
J 0
(520 6708);
DISPLAY 0.978723 (520 6708);
FORCEPROP 1 LAST VOLTAGE 25V
J 0
(520 6758);
DISPLAY 0.978723 (520 6758);
FORCEPROP 1 LAST PACK_TYPE C0402
J 0
(520 6558);
DISPLAY 0.978723 (520 6558);
FORCEPROP 1 LAST MATERIAL EMPTY
J 0
(520 6658);
DISPLAY 0.978723 (520 6658);
PAINT RED (520 6658);
FORCEPROP 1 LAST LOCATION PC2169
J 0
(520 6858);
DISPLAY 0.978723 (520 6858);
FORCEPROP 1 LAST PATH I48
J 0
(520 6908);
DISPLAY 0.978723 (520 6908);
PAINT WHITE (520 6908);
DISPLAY INVISIBLE (520 6908);
FORCEPROP 2 LAST CDS_LIB pure_quanta
J 0
(470 6758);
DISPLAY INVISIBLE (470 6758);
FORCEPROP 0 LAST $SEC 1
J 0
(520 6908);
DISPLAY INVISIBLE (520 6908);
FORCEPROP 0 LAST CDS_SEC 1
J 0
(520 6908);
DISPLAY INVISIBLE (520 6908);
FORCEPROP 1 LASTPIN (470 6858) $PN 1
J 0
(480 6838);
DISPLAY 0.787234 (480 6838);
PAINT MONO (480 6838);
DISPLAY INVISIBLE (480 6838);
FORCEPROP 1 LASTPIN (470 6658) $PN 2
J 0
(480 6638);
DISPLAY 0.787234 (480 6638);
PAINT MONO (480 6638);
DISPLAY INVISIBLE (480 6638);
FORCEADD UNIVERSAL_GND..1
(870 5883);
FORCEPROP 3 LASTPIN (870 5933) SIG_NAME GND\g
J 0
(880 5943);
DISPLAY 0.659574 (880 5943);
PAINT MONO (880 5943);
DISPLAY INVISIBLE (880 5943);
FORCEPROP 1 LAST HDL_POWER GND
J 1
(895 5808);
DISPLAY 0.872340 (895 5808);
PAINT GREEN (895 5808);
DISPLAY INVISIBLE (895 5808);
FORCEPROP 2 LAST CDS_LIB logical_power
J 0
(870 5883);
DISPLAY INVISIBLE (870 5883);
FORCEPROP 1 LAST PATH I49
J 0
(945 5883);
DISPLAY 0.872340 (945 5883);
PAINT AQUA (945 5883);
DISPLAY INVISIBLE (945 5883);
FORCEADD Q_CAP..1
(870 6108);
FORCEPROP 1 LAST PART_NUMBER CH3683K1B09
J 0
(920 5983);
DISPLAY 0.574468 (920 5983);
PAINT WHITE (920 5983);
DISPLAY INVISIBLE (920 5983);
FORCEPROP 2 LAST ROOM NIC1_P3V3_BOM2
J 0
(925 5925);
DISPLAY 0.510638 (925 5925);
FORCEPROP 1 LAST VOLTAGE 16V
J 0
(920 6083);
DISPLAY 0.574468 (920 6083);
PAINT SKYBLUE (920 6083);
FORCEPROP 1 LAST PACK_TYPE 0402
J 0
(920 6033);
DISPLAY 0.574468 (920 6033);
PAINT SKYBLUE (920 6033);
FORCEPROP 1 LAST MATERIAL EMPTY
J 0
(920 6133);
DISPLAY 0.574468 (920 6133);
PAINT RED (920 6133);
FORCEPROP 1 LAST VALUE 0.068UF
J 0
(920 6183);
DISPLAY 0.574468 (920 6183);
PAINT SKYBLUE (920 6183);
FORCEPROP 1 LAST LOCATION PC1321
J 0
(920 6208);
DISPLAY 0.723404 (920 6208);
PAINT AQUA (920 6208);
FORCEPROP 1 LAST PATH I50
J 0
(920 6258);
DISPLAY 0.978723 (920 6258);
PAINT WHITE (920 6258);
DISPLAY INVISIBLE (920 6258);
FORCEPROP 1 LAST TOLERANCE 10%
J 0
(920 6058);
DISPLAY 0.723404 (920 6058);
PAINT SKYBLUE (920 6058);
DISPLAY INVISIBLE (920 6058);
FORCEPROP 2 LAST CDS_LIB pure_quanta
J 0
(870 6108);
DISPLAY INVISIBLE (870 6108);
FORCEPROP 0 LAST $SEC 1
J 0
(920 6258);
DISPLAY INVISIBLE (920 6258);
FORCEPROP 0 LAST CDS_SEC 1
J 0
(920 6258);
DISPLAY INVISIBLE (920 6258);
FORCEPROP 1 LASTPIN (870 6208) $PN 1
J 0
(880 6188);
DISPLAY 0.787234 (880 6188);
PAINT MONO (880 6188);
DISPLAY INVISIBLE (880 6188);
FORCEPROP 1 LASTPIN (870 6008) $PN 2
J 0
(880 5988);
DISPLAY 0.787234 (880 5988);
PAINT MONO (880 5988);
DISPLAY INVISIBLE (880 5988);
FORCEADD MP5016GQHLZ..1
(1675 6425);
FORCEPROP 1 LAST PART_NUMBER AL005016007
J 0
(1430 6759);
DISPLAY 0.723404 (1430 6759);
PAINT GREEN (1430 6759);
DISPLAY INVISIBLE (1430 6759);
FORCEPROP 2 LAST ROOM NIC1_P3V3_BOM2
J 0
(1450 7050);
DISPLAY 0.808511 (1450 7050);
FORCEPROP 2 LAST VALUE MP5016GQH-L-Z
J 0
(1450 6950);
DISPLAY 0.680851 (1450 6950);
FORCEPROP 2 LAST PART_TYPE SMLF
J 0
(1450 7000);
DISPLAY 0.680851 (1450 7000);
FORCEPROP 1 LAST MATERIAL EMPTY
J 0
(1430 6632);
DISPLAY 0.723404 (1430 6632);
PAINT RED (1430 6632);
FORCEPROP 1 LAST LOCATION PU207
J 0
(1430 6906);
DISPLAY 0.723404 (1430 6906);
PAINT GREEN (1430 6906);
FORCEPROP 0 LASTPIN (1275 6275) $PN 10
J 2
(1265 6285);
DISPLAY 0.808511 (1265 6285);
FORCEPROP 0 LASTPIN (1275 6475) $PN 9
J 2
(1265 6485);
DISPLAY 0.808511 (1265 6485);
FORCEPROP 0 LASTPIN (2075 6375) $PN 8
J 0
(2085 6385);
DISPLAY 0.808511 (2085 6385);
FORCEPROP 0 LASTPIN (2075 6275) $PN 3
J 0
(2085 6285);
DISPLAY 0.808511 (2085 6285);
FORCEPROP 0 LASTPIN (1275 6325) $PN 4
J 2
(1265 6335);
DISPLAY 0.808511 (1265 6335);
FORCEPROP 0 LASTPIN (1275 6375) $PN 5
J 2
(1265 6385);
DISPLAY 0.808511 (1265 6385);
FORCEPROP 0 LASTPIN (2075 6575) $PN 6_7
J 0
(2085 6585);
DISPLAY 0.808511 (2085 6585);
FORCEPROP 0 LASTPIN (1275 6575) $PN 1_2
J 2
(1265 6585);
DISPLAY 0.808511 (1265 6585);
FORCEPROP 2 LAST CDS_LIB pure_quanta
J 0
(1675 6425);
DISPLAY INVISIBLE (1675 6425);
FORCEPROP 1 LAST CDS_LMAN_SYM_OUTLINE -250,200,250,-200
J 0
(1675 6425);
DISPLAY 0.468085 (1675 6425);
PAINT GREEN (1675 6425);
DISPLAY INVISIBLE (1675 6425);
FORCEPROP 1 LAST NEEDS_NO_SIZE TRUE
J 0
(1675 6425);
DISPLAY 0.723404 (1675 6425);
PAINT GREEN (1675 6425);
DISPLAY INVISIBLE (1675 6425);
FORCEPROP 1 LAST PATH I51
J 0
(1675 6425);
DISPLAY 0.723404 (1675 6425);
PAINT GREEN (1675 6425);
DISPLAY INVISIBLE (1675 6425);
FORCEPROP 0 LAST $SEC 1
J 0
(1450 7050);
DISPLAY INVISIBLE (1450 7050);
FORCEPROP 0 LAST CDS_SEC 1
J 0
(1450 7050);
DISPLAY INVISIBLE (1450 7050);
FORCEADD UNIVERSAL_POWER..1
R 2
(470 7083);
FORCEPROP 3 LASTPIN (470 7033) SIG_NAME P3V3_AUX\g
J 0
(480 7043);
DISPLAY 0.659574 (480 7043);
PAINT MONO (480 7043);
DISPLAY INVISIBLE (480 7043);
FORCEPROP 1 LAST HDL_POWER P3V3_AUX
J 1
(470 7133);
DISPLAY 0.723404 (470 7133);
PAINT GREEN (470 7133);
FORCEPROP 2 LAST CDS_LIB logical_power
J 0
(470 7083);
DISPLAY INVISIBLE (470 7083);
FORCEPROP 1 LAST PATH I52
J 2
(420 7108);
DISPLAY 0.872340 (420 7108);
PAINT AQUA (420 7108);
DISPLAY INVISIBLE (420 7108);
FORCEADD UNIVERSAL_GND..1
(2500 5800);
FORCEPROP 3 LASTPIN (2500 5850) SIG_NAME GND\g
J 0
(2510 5860);
DISPLAY 0.659574 (2510 5860);
PAINT MONO (2510 5860);
DISPLAY INVISIBLE (2510 5860);
FORCEPROP 1 LAST HDL_POWER GND
J 1
(2525 5725);
DISPLAY 0.872340 (2525 5725);
PAINT GREEN (2525 5725);
DISPLAY INVISIBLE (2525 5725);
FORCEPROP 2 LAST CDS_LIB logical_power
J 0
(2500 5800);
DISPLAY INVISIBLE (2500 5800);
FORCEPROP 1 LAST PATH I53
J 0
(2575 5800);
DISPLAY 0.872340 (2575 5800);
PAINT AQUA (2575 5800);
DISPLAY INVISIBLE (2575 5800);
FORCEADD Q_CAP..1
(2500 6150);
FORCEPROP 1 LAST PART_NUMBER CH11006JB18
J 0
(2550 5975);
DISPLAY 0.574468 (2550 5975);
PAINT WHITE (2550 5975);
DISPLAY INVISIBLE (2550 5975);
FORCEPROP 2 LAST ROOM NIC1_P3V3_BOM2
J 0
(2550 6275);
DISPLAY 0.404255 (2550 6275);
FORCEPROP 1 LAST MATERIAL EMPTY
J 0
(2550 6125);
DISPLAY 0.574468 (2550 6125);
PAINT RED (2550 6125);
FORCEPROP 1 LAST PACK_TYPE 0402
J 0
(2550 6025);
DISPLAY 0.574468 (2550 6025);
PAINT SKYBLUE (2550 6025);
FORCEPROP 1 LAST VOLTAGE 50V
J 0
(2550 6075);
DISPLAY 0.574468 (2550 6075);
PAINT SKYBLUE (2550 6075);
FORCEPROP 1 LAST VALUE 100PF
J 0
(2550 6175);
DISPLAY 0.574468 (2550 6175);
PAINT SKYBLUE (2550 6175);
FORCEPROP 1 LAST LOCATION PC1322
J 0
(2550 6225);
DISPLAY 0.723404 (2550 6225);
PAINT AQUA (2550 6225);
FORCEPROP 1 LAST PATH I54
J 0
(2550 6300);
DISPLAY 0.978723 (2550 6300);
PAINT WHITE (2550 6300);
DISPLAY INVISIBLE (2550 6300);
FORCEPROP 2 LAST CDS_LIB pure_quanta
J 0
(2500 6150);
DISPLAY INVISIBLE (2500 6150);
FORCEPROP 1 LAST TOLERANCE 5%
J 0
(2550 6100);
DISPLAY 0.723404 (2550 6100);
PAINT SKYBLUE (2550 6100);
DISPLAY INVISIBLE (2550 6100);
FORCEPROP 0 LAST $SEC 1
J 0
(2550 6275);
DISPLAY INVISIBLE (2550 6275);
FORCEPROP 0 LAST CDS_SEC 1
J 0
(2550 6275);
DISPLAY INVISIBLE (2550 6275);
FORCEPROP 1 LASTPIN (2500 6250) $PN 1
J 0
(2510 6230);
DISPLAY 0.787234 (2510 6230);
PAINT MONO (2510 6230);
DISPLAY INVISIBLE (2510 6230);
FORCEPROP 1 LASTPIN (2500 6050) $PN 2
J 0
(2510 6030);
DISPLAY 0.787234 (2510 6030);
PAINT MONO (2510 6030);
DISPLAY INVISIBLE (2510 6030);
FORCEADD UNIVERSAL_GND..1
(2900 6000);
FORCEPROP 3 LASTPIN (2900 6050) SIG_NAME GND\g
J 0
(2910 6060);
DISPLAY 0.659574 (2910 6060);
PAINT MONO (2910 6060);
DISPLAY INVISIBLE (2910 6060);
FORCEPROP 1 LAST HDL_POWER GND
J 1
(2925 5925);
DISPLAY 0.872340 (2925 5925);
PAINT GREEN (2925 5925);
DISPLAY INVISIBLE (2925 5925);
FORCEPROP 2 LAST CDS_LIB logical_power
J 0
(2900 6000);
DISPLAY INVISIBLE (2900 6000);
FORCEPROP 1 LAST PATH I55
J 0
(2975 6000);
DISPLAY 0.872340 (2975 6000);
PAINT AQUA (2975 6000);
DISPLAY INVISIBLE (2975 6000);
FORCEADD Q_CAP..1
(2900 6350);
FORCEPROP 1 LAST PART_NUMBER CH6103KEA01
J 0
(2950 6200);
DISPLAY 0.787234 (2950 6200);
DISPLAY INVISIBLE (2950 6200);
FORCEPROP 2 LAST ROOM NIC1_P3V3_BOM2
J 0
(2950 6500);
DISPLAY 0.510638 (2950 6500);
FORCEPROP 1 LAST TOLERANCE 10%
J 0
(2950 6300);
DISPLAY 0.787234 (2950 6300);
FORCEPROP 1 LAST MATERIAL EMPTY
J 0
(2950 6250);
DISPLAY 0.787234 (2950 6250);
PAINT RED (2950 6250);
FORCEPROP 1 LAST PACK_TYPE C0805
J 0
(2950 6150);
DISPLAY 0.787234 (2950 6150);
FORCEPROP 1 LAST VALUE 10UF
J 0
(2950 6400);
DISPLAY 0.787234 (2950 6400);
FORCEPROP 1 LAST VOLTAGE 16V
J 0
(2950 6350);
DISPLAY 0.787234 (2950 6350);
FORCEPROP 1 LAST LOCATION PC2173
J 0
(2950 6450);
DISPLAY 0.787234 (2950 6450);
FORCEPROP 1 LAST PATH I56
J 0
(2950 6500);
DISPLAY 0.978723 (2950 6500);
PAINT WHITE (2950 6500);
DISPLAY INVISIBLE (2950 6500);
FORCEPROP 2 LAST CDS_LIB pure_quanta
J 0
(2900 6350);
DISPLAY INVISIBLE (2900 6350);
FORCEPROP 0 LAST $SEC 1
J 0
(2950 6500);
DISPLAY INVISIBLE (2950 6500);
FORCEPROP 0 LAST CDS_SEC 1
J 0
(2950 6500);
DISPLAY INVISIBLE (2950 6500);
FORCEPROP 1 LASTPIN (2900 6450) $PN 1
J 0
(2910 6430);
DISPLAY 0.787234 (2910 6430);
PAINT MONO (2910 6430);
DISPLAY INVISIBLE (2910 6430);
FORCEPROP 1 LASTPIN (2900 6250) $PN 2
J 0
(2910 6230);
DISPLAY 0.787234 (2910 6230);
PAINT MONO (2910 6230);
DISPLAY INVISIBLE (2910 6230);
FORCEADD UNIVERSAL_POWER..1
R 2
(2900 6900);
FORCEPROP 3 LASTPIN (2900 6850) SIG_NAME P3V3_OCP_V3_2_R\g
J 0
(2910 6860);
DISPLAY 0.659574 (2910 6860);
PAINT MONO (2910 6860);
DISPLAY INVISIBLE (2910 6860);
FORCEPROP 1 LAST HDL_POWER P3V3_OCP_V3_2_R
J 1
(2900 6950);
DISPLAY 0.723404 (2900 6950);
PAINT GREEN (2900 6950);
FORCEPROP 2 LAST CDS_LIB logical_power
J 0
(2900 6900);
DISPLAY INVISIBLE (2900 6900);
FORCEPROP 1 LAST PATH I57
J 2
(2850 6925);
DISPLAY 0.872340 (2850 6925);
PAINT AQUA (2850 6925);
DISPLAY INVISIBLE (2850 6925);
FORCEADD OFFPAGE..1
(-4900 3175);
PAINT AQUA (-4900 3175);
FORCEPROP 2 LAST $XR0 164 
J 0
(-5182 3175);
DISPLAY 0.638298 (-5182 3175);
PAINT MONO (-5182 3175);
FORCEPROP 2 LAST $XR1 162 
J 0
(-5302 3175);
DISPLAY 0.638298 (-5302 3175);
PAINT MONO (-5302 3175);
FORCEPROP 2 LAST $XR2 163 
J 0
(-5422 3175);
DISPLAY 0.638298 (-5422 3175);
PAINT MONO (-5422 3175);
FORCEPROP 2 LAST $XR3 238 
J 0
(-5542 3175);
DISPLAY 0.638298 (-5542 3175);
PAINT MONO (-5542 3175);
FORCEPROP 2 LAST PATH I58
J 0
(-5150 3225);
DISPLAY 1.021277 (-5150 3225);
DISPLAY INVISIBLE (-5150 3225);
FORCEPROP 2 LAST CDS_LIB standard
J 0
(-4900 3175);
DISPLAY INVISIBLE (-4900 3175);
FORCEPROP 1 LAST OFFPAGE TRUE
J 0
(-4575 3050);
DISPLAY 0.872340 (-4575 3050);
PAINT AQUA (-4575 3050);
DISPLAY INVISIBLE (-4575 3050);
FORCEPROP 1 LAST COMMENT_BODY TRUE
J 0
(-4775 3075);
DISPLAY 0.872340 (-4775 3075);
PAINT GREEN (-4775 3075);
DISPLAY INVISIBLE (-4775 3075);
FORCEADD GND..1
(-4175 2375);
FORCEPROP 3 LASTPIN (-4175 2425) SIG_NAME GND\g
J 0
(-4165 2435);
DISPLAY 0.659574 (-4165 2435);
PAINT MONO (-4165 2435);
DISPLAY INVISIBLE (-4165 2435);
FORCEPROP 1 LAST PATH I59
J 0
(-4100 2375);
DISPLAY 0.872340 (-4100 2375);
PAINT AQUA (-4100 2375);
DISPLAY INVISIBLE (-4100 2375);
FORCEPROP 1 LAST SIZE 1B
J 0
(-4100 2325);
DISPLAY 0.872340 (-4100 2325);
PAINT GREEN (-4100 2325);
DISPLAY INVISIBLE (-4100 2325);
FORCEPROP 2 LAST CDS_LIB logical_power
J 0
(-4175 2375);
DISPLAY INVISIBLE (-4175 2375);
FORCEPROP 1 LAST HDL_POWER GND
J 0
(-4175 2525);
DISPLAY 0.872340 (-4175 2525);
PAINT GREEN (-4175 2525);
DISPLAY INVISIBLE (-4175 2525);
FORCEADD GND..1
(-3750 2300);
FORCEPROP 3 LASTPIN (-3750 2350) SIG_NAME GND\g
J 0
(-3740 2360);
DISPLAY 0.659574 (-3740 2360);
PAINT MONO (-3740 2360);
DISPLAY INVISIBLE (-3740 2360);
FORCEPROP 1 LAST PATH I60
J 0
(-3675 2300);
DISPLAY 0.872340 (-3675 2300);
PAINT AQUA (-3675 2300);
DISPLAY INVISIBLE (-3675 2300);
FORCEPROP 2 LAST CDS_LIB logical_power
J 0
(-3750 2300);
DISPLAY INVISIBLE (-3750 2300);
FORCEPROP 1 LAST SIZE 1B
J 0
(-3675 2250);
DISPLAY 0.872340 (-3675 2250);
PAINT GREEN (-3675 2250);
DISPLAY INVISIBLE (-3675 2250);
FORCEPROP 1 LAST HDL_POWER GND
J 0
(-3750 2450);
DISPLAY 0.872340 (-3750 2450);
PAINT GREEN (-3750 2450);
DISPLAY INVISIBLE (-3750 2450);
FORCEADD Q_RES..2
(-3750 2575);
FORCEPROP 1 LAST PART_NUMBER CS31432FB02
J 0
(-3710 2450);
DISPLAY 0.638298 (-3710 2450);
DISPLAY INVISIBLE (-3710 2450);
FORCEPROP 2 LAST ROOM NIC1_P12V_MPS_MAM_BOM3
J 0
(-3700 2750);
DISPLAY 1.021277 (-3700 2750);
FORCEPROP 1 LAST VALUE 14.3K
J 0
(-3705 2650);
DISPLAY 0.638298 (-3705 2650);
FORCEPROP 1 LAST MATERIAL CHIP
J 0
(-3710 2500);
DISPLAY 0.638298 (-3710 2500);
FORCEPROP 1 LAST TOLERANCE 1%
J 0
(-3705 2600);
DISPLAY 0.638298 (-3705 2600);
FORCEPROP 1 LAST PACK_TYPE 0402LF
J 0
(-3710 2400);
DISPLAY 0.638298 (-3710 2400);
FORCEPROP 1 LAST WATTAGE 1/16W
J 0
(-3710 2550);
DISPLAY 0.638298 (-3710 2550);
FORCEPROP 1 LAST LOCATION PR3847
J 0
(-3705 2700);
DISPLAY 0.638298 (-3705 2700);
FORCEPROP 1 LASTPIN (-3750 2675) $PN 1
J 0
(-3745 2637);
DISPLAY 0.787234 (-3745 2637);
PAINT MONO (-3745 2637);
FORCEPROP 1 LASTPIN (-3750 2475) $PN 2
J 0
(-3745 2485);
DISPLAY 0.787234 (-3745 2485);
PAINT MONO (-3745 2485);
FORCEPROP 2 LAST ROOM1 NIC1_P12V_MPS_TIC_BOM4
J 0
(-3700 2800);
DISPLAY 1.021277 (-3700 2800);
DISPLAY INVISIBLE (-3700 2800);
FORCEPROP 2 LAST CDS_LIB pure_quanta
J 0
(-3750 2575);
DISPLAY INVISIBLE (-3750 2575);
FORCEPROP 1 LAST PATH I61
J 0
(-3700 2750);
DISPLAY 0.978723 (-3700 2750);
PAINT WHITE (-3700 2750);
DISPLAY INVISIBLE (-3700 2750);
FORCEPROP 0 LAST $SEC 1
J 0
(-3695 2742);
DISPLAY 0.680851 (-3695 2742);
PAINT MONO (-3695 2742);
DISPLAY INVISIBLE (-3695 2742);
FORCEPROP 0 LAST CDS_SEC 1
J 0
(-3700 2725);
DISPLAY INVISIBLE (-3700 2725);
FORCEADD Q_CAP..1
(-4175 2725);
FORCEPROP 1 LAST PART_NUMBER CH4223K1B00
J 0
(-4125 2575);
DISPLAY 0.638298 (-4125 2575);
DISPLAY INVISIBLE (-4125 2575);
FORCEPROP 1 LAST PACK_TYPE 0402
J 0
(-4130 2633);
DISPLAY 0.638298 (-4130 2633);
FORCEPROP 1 LAST MATERIAL X7R
J 0
(-4130 2683);
DISPLAY 0.638298 (-4130 2683);
FORCEPROP 2 LAST ROOM NIC1_P12V_MPS_MAM_BOM3
J 0
(-4125 2875);
DISPLAY 1.021277 (-4125 2875);
FORCEPROP 1 LAST VALUE 0.22UF
J 0
(-4125 2775);
DISPLAY 0.638298 (-4125 2775);
FORCEPROP 1 LAST VOLTAGE 16V
J 0
(-4125 2725);
DISPLAY 0.638298 (-4125 2725);
FORCEPROP 1 LAST LOCATION PC2164
J 0
(-4125 2825);
DISPLAY 0.808511 (-4125 2825);
FORCEPROP 2 LAST ROOM1 NIC1_P12V_MPS_TIC_BOM4
J 0
(-4125 2925);
DISPLAY 1.021277 (-4125 2925);
DISPLAY INVISIBLE (-4125 2925);
FORCEPROP 2 LAST CDS_LIB pure_quanta
J 0
(-4175 2725);
DISPLAY INVISIBLE (-4175 2725);
FORCEPROP 1 LAST TOLERANCE 10%
J 0
(-4125 2675);
DISPLAY 0.638298 (-4125 2675);
DISPLAY INVISIBLE (-4125 2675);
FORCEPROP 1 LAST PATH I62
J 0
(-4125 2875);
DISPLAY 0.978723 (-4125 2875);
PAINT WHITE (-4125 2875);
DISPLAY INVISIBLE (-4125 2875);
FORCEPROP 0 LAST $SEC 1
J 0
(-4105 2883);
DISPLAY INVISIBLE (-4105 2883);
FORCEPROP 0 LAST CDS_SEC 1
J 0
(-4105 2883);
DISPLAY INVISIBLE (-4105 2883);
FORCEPROP 1 LASTPIN (-4175 2825) $PN 1
J 0
(-4165 2805);
DISPLAY 0.787234 (-4165 2805);
PAINT MONO (-4165 2805);
DISPLAY INVISIBLE (-4165 2805);
FORCEPROP 1 LASTPIN (-4175 2625) $PN 2
J 0
(-4165 2605);
DISPLAY 0.787234 (-4165 2605);
PAINT MONO (-4165 2605);
DISPLAY INVISIBLE (-4165 2605);
FORCEADD GND..1
(-3775 2925);
FORCEPROP 3 LASTPIN (-3775 2975) SIG_NAME GND\g
J 0
(-3765 2985);
DISPLAY 0.659574 (-3765 2985);
PAINT MONO (-3765 2985);
DISPLAY INVISIBLE (-3765 2985);
FORCEPROP 1 LAST PATH I63
J 0
(-3700 2925);
DISPLAY 0.872340 (-3700 2925);
PAINT AQUA (-3700 2925);
DISPLAY INVISIBLE (-3700 2925);
FORCEPROP 1 LAST SIZE 1B
J 0
(-3700 2875);
DISPLAY 0.872340 (-3700 2875);
PAINT GREEN (-3700 2875);
DISPLAY INVISIBLE (-3700 2875);
FORCEPROP 2 LAST CDS_LIB logical_power
J 0
(-3775 2925);
DISPLAY INVISIBLE (-3775 2925);
FORCEPROP 1 LAST HDL_POWER GND
J 0
(-3775 3075);
DISPLAY 0.872340 (-3775 3075);
PAINT GREEN (-3775 3075);
DISPLAY INVISIBLE (-3775 3075);
FORCEADD GND..1
(-3330 2258);
FORCEPROP 3 LASTPIN (-3330 2308) SIG_NAME GND\g
J 0
(-3320 2318);
DISPLAY 0.659574 (-3320 2318);
PAINT MONO (-3320 2318);
DISPLAY INVISIBLE (-3320 2318);
FORCEPROP 1 LAST PATH I64
J 0
(-3255 2258);
DISPLAY 0.872340 (-3255 2258);
PAINT AQUA (-3255 2258);
DISPLAY INVISIBLE (-3255 2258);
FORCEPROP 2 LAST CDS_LIB logical_power
J 0
(-3330 2258);
DISPLAY INVISIBLE (-3330 2258);
FORCEPROP 1 LAST SIZE 1B
J 0
(-3255 2208);
DISPLAY 0.872340 (-3255 2208);
PAINT GREEN (-3255 2208);
DISPLAY INVISIBLE (-3255 2208);
FORCEPROP 1 LAST HDL_POWER GND
J 0
(-3330 2408);
DISPLAY 0.872340 (-3330 2408);
PAINT GREEN (-3330 2408);
DISPLAY INVISIBLE (-3330 2408);
FORCEADD Q_CAP..1
(-3330 2508);
FORCEPROP 1 LAST PART_NUMBER CH3474K1B04
J 0
(-3288 2357);
DISPLAY 0.638298 (-3288 2357);
DISPLAY INVISIBLE (-3288 2357);
FORCEPROP 2 LAST ROOM NIC1_P12V_MPS_MAM_BOM3
J 0
(-3275 2650);
DISPLAY 1.021277 (-3275 2650);
FORCEPROP 1 LAST PACK_TYPE C0402
J 0
(-3288 2407);
DISPLAY 0.638298 (-3288 2407);
FORCEPROP 1 LAST VOLTAGE 25V
J 0
(-3288 2457);
DISPLAY 0.638298 (-3288 2457);
FORCEPROP 1 LAST MATERIAL X7R
J 0
(-3288 2507);
DISPLAY 0.638298 (-3288 2507);
FORCEPROP 1 LAST VALUE 0.047UF
J 0
(-3280 2558);
DISPLAY 0.638298 (-3280 2558);
FORCEPROP 1 LAST LOCATION PC2166
J 0
(-3280 2608);
DISPLAY 0.787234 (-3280 2608);
FORCEPROP 2 LAST ROOM1 NIC1_P12V_MPS_TIC_BOM4
J 0
(-3275 2700);
DISPLAY 1.021277 (-3275 2700);
DISPLAY INVISIBLE (-3275 2700);
FORCEPROP 2 LAST CDS_LIB pure_quanta
J 0
(-3330 2508);
DISPLAY INVISIBLE (-3330 2508);
FORCEPROP 1 LAST TOLERANCE 10%
J 0
(-3280 2458);
DISPLAY 0.638298 (-3280 2458);
DISPLAY INVISIBLE (-3280 2458);
FORCEPROP 1 LAST PATH I65
J 0
(-3280 2658);
DISPLAY 0.978723 (-3280 2658);
PAINT WHITE (-3280 2658);
DISPLAY INVISIBLE (-3280 2658);
FORCEPROP 0 LAST $SEC 1
J 0
(-3280 2658);
DISPLAY INVISIBLE (-3280 2658);
FORCEPROP 0 LAST CDS_SEC 1
J 0
(-3280 2658);
DISPLAY INVISIBLE (-3280 2658);
FORCEPROP 1 LASTPIN (-3330 2608) $PN 1
J 0
(-3320 2588);
DISPLAY 0.787234 (-3320 2588);
PAINT MONO (-3320 2588);
DISPLAY INVISIBLE (-3320 2588);
FORCEPROP 1 LASTPIN (-3330 2408) $PN 2
J 0
(-3320 2388);
DISPLAY 0.787234 (-3320 2388);
PAINT MONO (-3320 2388);
DISPLAY INVISIBLE (-3320 2388);
FORCEADD Q_RES..1
(-4075 3175);
FORCEPROP 1 LAST PART_NUMBER CS00002JB13
J 0
(-4150 3125);
DISPLAY 0.510638 (-4150 3125);
DISPLAY INVISIBLE (-4150 3125);
FORCEPROP 2 LAST ROOM NIC1_P12V_MPS_MAM_BOM3
J 0
(-4125 3275);
DISPLAY 1.021277 (-4125 3275);
FORCEPROP 1 LAST PACK_TYPE 0402LF
J 0
(-3825 3175);
DISPLAY 0.510638 (-3825 3175);
FORCEPROP 1 LAST MATERIAL CHIP
J 0
(-4150 3100);
DISPLAY 0.510638 (-4150 3100);
FORCEPROP 1 LAST WATTAGE 1/16W
J 2
(-3875 3100);
DISPLAY 0.510638 (-3875 3100);
FORCEPROP 1 LAST VALUE 0
J 2
(-3925 3175);
DISPLAY 0.510638 (-3925 3175);
FORCEPROP 1 LAST TOLERANCE 5%
J 0
(-3900 3175);
DISPLAY 0.510638 (-3900 3175);
FORCEPROP 1 LAST $LOCATION R3630
J 0
(-4125 3225);
DISPLAY 0.978723 (-4125 3225);
FORCEPROP 1 LASTPIN (-4175 3175) $PN 1
J 0
(-4163 3187);
DISPLAY 0.787234 (-4163 3187);
PAINT MONO (-4163 3187);
FORCEPROP 1 LASTPIN (-3975 3175) $PN 2
J 0
(-4013 3187);
DISPLAY 0.787234 (-4013 3187);
PAINT MONO (-4013 3187);
FORCEPROP 2 LAST ROOM1 NIC1_P12V_MPS_TIC_BOM4
J 0
(-4125 3325);
DISPLAY 1.021277 (-4125 3325);
DISPLAY INVISIBLE (-4125 3325);
FORCEPROP 2 LAST CDS_LIB pure_quanta
J 0
(-4075 3175);
DISPLAY INVISIBLE (-4075 3175);
FORCEPROP 1 LAST PATH I66
J 0
(-4125 3325);
DISPLAY 0.978723 (-4125 3325);
PAINT WHITE (-4125 3325);
DISPLAY INVISIBLE (-4125 3325);
FORCEPROP 0 LAST CDS_LOCATION R3630
J 0
(-4125 3275);
DISPLAY 1.021277 (-4125 3275);
DISPLAY INVISIBLE (-4125 3275);
FORCEPROP 0 LAST $SEC 1
J 0
(-4125 3275);
DISPLAY 0.680851 (-4125 3275);
PAINT MONO (-4125 3275);
DISPLAY INVISIBLE (-4125 3275);
FORCEPROP 0 LAST CDS_SEC 1
J 0
(-4125 3275);
DISPLAY 1.021277 (-4125 3275);
DISPLAY INVISIBLE (-4125 3275);
FORCEADD GND..1
(-3500 3300);
FORCEPROP 3 LASTPIN (-3500 3350) SIG_NAME GND\g
J 0
(-3490 3360);
DISPLAY 0.659574 (-3490 3360);
PAINT MONO (-3490 3360);
DISPLAY INVISIBLE (-3490 3360);
FORCEPROP 1 LAST PATH I67
J 0
(-3425 3300);
DISPLAY 0.872340 (-3425 3300);
PAINT AQUA (-3425 3300);
DISPLAY INVISIBLE (-3425 3300);
FORCEPROP 1 LAST SIZE 1B
J 0
(-3425 3250);
DISPLAY 0.872340 (-3425 3250);
PAINT GREEN (-3425 3250);
DISPLAY INVISIBLE (-3425 3250);
FORCEPROP 2 LAST CDS_LIB logical_power
J 0
(-3500 3300);
DISPLAY INVISIBLE (-3500 3300);
FORCEPROP 1 LAST HDL_POWER GND
J 0
(-3500 3450);
DISPLAY 0.872340 (-3500 3450);
PAINT GREEN (-3500 3450);
DISPLAY INVISIBLE (-3500 3450);
FORCEADD Q_CAP..1
(-3500 3675);
FORCEPROP 1 LAST PART_NUMBER CH5104KEB02
J 0
(-3450 3525);
DISPLAY 0.638298 (-3450 3525);
DISPLAY INVISIBLE (-3450 3525);
FORCEPROP 2 LAST ROOM NIC1_P12V_MPS_MAM_BOM3
J 0
(-3450 3825);
DISPLAY 1.021277 (-3450 3825);
FORCEPROP 1 LAST MATERIAL X6S
J 0
(-3450 3625);
DISPLAY 0.638298 (-3450 3625);
FORCEPROP 1 LAST PACK_TYPE C0402
J 0
(-3450 3575);
DISPLAY 0.638298 (-3450 3575);
FORCEPROP 1 LAST VOLTAGE 25V
J 0
(-3450 3675);
DISPLAY 0.638298 (-3450 3675);
FORCEPROP 1 LAST VALUE 1UF
J 0
(-3450 3725);
DISPLAY 0.638298 (-3450 3725);
FORCEPROP 1 LAST LOCATION PC2165
J 0
(-3450 3775);
DISPLAY 0.787234 (-3450 3775);
FORCEPROP 2 LAST ROOM1 NIC1_P12V_MPS_TIC_BOM4
J 0
(-3450 3875);
DISPLAY 1.021277 (-3450 3875);
DISPLAY INVISIBLE (-3450 3875);
FORCEPROP 2 LAST CDS_LIB pure_quanta
J 0
(-3500 3675);
DISPLAY INVISIBLE (-3500 3675);
FORCEPROP 1 LAST TOLERANCE 10%
J 0
(-3450 3625);
DISPLAY 0.638298 (-3450 3625);
DISPLAY INVISIBLE (-3450 3625);
FORCEPROP 1 LAST PATH I68
J 0
(-3450 3825);
DISPLAY 0.978723 (-3450 3825);
PAINT WHITE (-3450 3825);
DISPLAY INVISIBLE (-3450 3825);
FORCEPROP 0 LAST $SEC 1
J 0
(-3450 3825);
DISPLAY INVISIBLE (-3450 3825);
FORCEPROP 0 LAST CDS_SEC 1
J 0
(-3450 3825);
DISPLAY INVISIBLE (-3450 3825);
FORCEPROP 1 LASTPIN (-3500 3775) $PN 1
J 0
(-3490 3755);
DISPLAY 0.787234 (-3490 3755);
PAINT MONO (-3490 3755);
DISPLAY INVISIBLE (-3490 3755);
FORCEPROP 1 LASTPIN (-3500 3575) $PN 2
J 0
(-3490 3555);
DISPLAY 0.787234 (-3490 3555);
PAINT MONO (-3490 3555);
DISPLAY INVISIBLE (-3490 3555);
FORCEADD GND..1
(-3009 2441);
FORCEPROP 3 LASTPIN (-3009 2491) SIG_NAME GND\g
J 0
(-2999 2501);
DISPLAY 0.659574 (-2999 2501);
PAINT MONO (-2999 2501);
DISPLAY INVISIBLE (-2999 2501);
FORCEPROP 1 LAST PATH I69
J 0
(-2934 2441);
DISPLAY 0.872340 (-2934 2441);
PAINT AQUA (-2934 2441);
DISPLAY INVISIBLE (-2934 2441);
FORCEPROP 1 LAST SIZE 1B
J 0
(-2934 2391);
DISPLAY 0.872340 (-2934 2391);
PAINT GREEN (-2934 2391);
DISPLAY INVISIBLE (-2934 2391);
FORCEPROP 2 LAST CDS_LIB logical_power
J 0
(-3009 2441);
DISPLAY INVISIBLE (-3009 2441);
FORCEPROP 1 LAST HDL_POWER GND
J 0
(-3009 2591);
DISPLAY 0.872340 (-3009 2591);
PAINT GREEN (-3009 2591);
DISPLAY INVISIBLE (-3009 2591);
FORCEADD RS31312R..1
(-2550 3050);
FORCEPROP 1 LAST PART_NUMBER AL031312000
J 0
(-2800 3750);
DISPLAY 0.723404 (-2800 3750);
PAINT GREEN (-2800 3750);
DISPLAY INVISIBLE (-2800 3750);
FORCEPROP 2 LAST ROOM NIC1_P12V_MPS_MAM_BOM3
J 0
(-2775 3900);
DISPLAY 1.021277 (-2775 3900);
FORCEPROP 2 LAST VALUE RS31312R
J 0
(-2800 3675);
DISPLAY 0.808511 (-2800 3675);
FORCEPROP 1 LAST MATERIAL IC
J 0
(-2797 3587);
DISPLAY 0.723404 (-2797 3587);
PAINT GREEN (-2797 3587);
FORCEPROP 1 LAST LOCATION PU206
J 0
(-2797 3861);
DISPLAY 0.723404 (-2797 3861);
PAINT GREEN (-2797 3861);
FORCEPROP 0 LASTPIN (-2150 2925) $PN 12
J 0
(-2140 2935);
DISPLAY 0.680851 (-2140 2935);
PAINT MONO (-2140 2935);
FORCEPROP 0 LASTPIN (-2950 3175) $PN 1
J 2
(-2960 3185);
DISPLAY 0.680851 (-2960 3185);
PAINT MONO (-2960 3185);
FORCEPROP 0 LASTPIN (-2950 2975) $PN 3
J 2
(-2960 2985);
DISPLAY 0.680851 (-2960 2985);
PAINT MONO (-2960 2985);
FORCEPROP 0 LASTPIN (-2150 2675) $PN 9
J 0
(-2140 2685);
DISPLAY 0.680851 (-2140 2685);
PAINT MONO (-2140 2685);
FORCEPROP 0 LASTPIN (-2950 2575) $PN 7
J 2
(-2960 2585);
DISPLAY 0.680851 (-2960 2585);
PAINT MONO (-2960 2585);
FORCEPROP 0 LASTPIN (-2150 2575) $PN 8
J 0
(-2140 2585);
DISPLAY 0.680851 (-2140 2585);
PAINT MONO (-2140 2585);
FORCEPROP 0 LASTPIN (-2950 2775) $PN 5
J 2
(-2960 2785);
DISPLAY 0.680851 (-2960 2785);
PAINT MONO (-2960 2785);
FORCEPROP 0 LASTPIN (-2950 3075) $PN 2
J 2
(-2960 3085);
DISPLAY 0.680851 (-2960 3085);
PAINT MONO (-2960 3085);
FORCEPROP 0 LASTPIN (-2150 2825) $PN 11
J 0
(-2140 2835);
DISPLAY 0.680851 (-2140 2835);
PAINT MONO (-2140 2835);
FORCEPROP 0 LASTPIN (-2150 3525) $PN 10
J 0
(-2140 3535);
DISPLAY 0.680851 (-2140 3535);
PAINT MONO (-2140 3535);
FORCEPROP 0 LASTPIN (-2950 2675) $PN 6
J 2
(-2960 2685);
DISPLAY 0.680851 (-2960 2685);
PAINT MONO (-2960 2685);
FORCEPROP 0 LASTPIN (-2950 2875) $PN 4
J 2
(-2960 2885);
DISPLAY 0.680851 (-2960 2885);
PAINT MONO (-2960 2885);
FORCEPROP 0 LASTPIN (-2950 3525) $PN 21_22
J 2
(-2960 3535);
DISPLAY 0.680851 (-2960 3535);
PAINT MONO (-2960 3535);
FORCEPROP 0 LASTPIN (-2950 3475) $PN 23
J 2
(-2960 3485);
DISPLAY 0.680851 (-2960 3485);
PAINT MONO (-2960 3485);
FORCEPROP 0 LASTPIN (-2950 3425) $PN 24
J 2
(-2960 3435);
DISPLAY 0.680851 (-2960 3435);
PAINT MONO (-2960 3435);
FORCEPROP 0 LASTPIN (-2950 3375) $PN 25
J 2
(-2960 3385);
DISPLAY 0.680851 (-2960 3385);
PAINT MONO (-2960 3385);
FORCEPROP 0 LASTPIN (-2950 3325) $PN 26
J 2
(-2960 3335);
DISPLAY 0.680851 (-2960 3335);
PAINT MONO (-2960 3335);
FORCEPROP 0 LASTPIN (-2150 3025) $PN 13
J 0
(-2140 3035);
DISPLAY 0.680851 (-2140 3035);
PAINT MONO (-2140 3035);
FORCEPROP 0 LASTPIN (-2150 3075) $PN 14
J 0
(-2140 3085);
DISPLAY 0.680851 (-2140 3085);
PAINT MONO (-2140 3085);
FORCEPROP 0 LASTPIN (-2150 3125) $PN 15
J 0
(-2140 3135);
DISPLAY 0.680851 (-2140 3135);
PAINT MONO (-2140 3135);
FORCEPROP 0 LASTPIN (-2150 3175) $PN 16
J 0
(-2140 3185);
DISPLAY 0.680851 (-2140 3185);
PAINT MONO (-2140 3185);
FORCEPROP 0 LASTPIN (-2150 3225) $PN 17
J 0
(-2140 3235);
DISPLAY 0.680851 (-2140 3235);
PAINT MONO (-2140 3235);
FORCEPROP 0 LASTPIN (-2150 3275) $PN 18
J 0
(-2140 3285);
DISPLAY 0.680851 (-2140 3285);
PAINT MONO (-2140 3285);
FORCEPROP 0 LASTPIN (-2150 3325) $PN 19
J 0
(-2140 3335);
DISPLAY 0.680851 (-2140 3335);
PAINT MONO (-2140 3335);
FORCEPROP 0 LASTPIN (-2150 3375) $PN 20
J 0
(-2140 3385);
DISPLAY 0.680851 (-2140 3385);
PAINT MONO (-2140 3385);
FORCEPROP 2 LAST ROOM1 NIC1_P12V_MPS_TIC_BOM4
J 0
(-2775 3950);
DISPLAY 1.021277 (-2775 3950);
DISPLAY INVISIBLE (-2775 3950);
FORCEPROP 0 LAST PART_TYPE SMLF
J 0
(-2803 3835);
DISPLAY 1.021277 (-2803 3835);
DISPLAY INVISIBLE (-2803 3835);
FORCEPROP 2 LAST CDS_LIB pure_quanta
J 0
(-2550 3050);
DISPLAY INVISIBLE (-2550 3050);
FORCEPROP 1 LAST NEEDS_NO_SIZE TRUE
J 0
(-2550 3050);
DISPLAY 0.723404 (-2550 3050);
PAINT GREEN (-2550 3050);
DISPLAY INVISIBLE (-2550 3050);
FORCEPROP 1 LAST CDS_LMAN_SYM_OUTLINE -250,525,250,-525
J 0
(-2550 3050);
DISPLAY 0.468085 (-2550 3050);
PAINT GREEN (-2550 3050);
DISPLAY INVISIBLE (-2550 3050);
FORCEPROP 1 LAST PATH I70
J 0
(-2550 3050);
DISPLAY 0.723404 (-2550 3050);
PAINT GREEN (-2550 3050);
DISPLAY INVISIBLE (-2550 3050);
FORCEPROP 0 LAST $SEC 1
J 0
(-2775 3950);
DISPLAY 0.680851 (-2775 3950);
PAINT MONO (-2775 3950);
DISPLAY INVISIBLE (-2775 3950);
FORCEPROP 0 LAST CDS_SEC 1
J 0
(-2705 3633);
DISPLAY INVISIBLE (-2705 3633);
FORCEADD GND..1
(-1550 1950);
FORCEPROP 3 LASTPIN (-1550 2000) SIG_NAME GND\g
J 0
(-1540 2010);
DISPLAY 0.659574 (-1540 2010);
PAINT MONO (-1540 2010);
DISPLAY INVISIBLE (-1540 2010);
FORCEPROP 1 LAST PATH I71
J 0
(-1475 1950);
DISPLAY 0.872340 (-1475 1950);
PAINT AQUA (-1475 1950);
DISPLAY INVISIBLE (-1475 1950);
FORCEPROP 2 LAST CDS_LIB logical_power
J 0
(-1550 1950);
DISPLAY INVISIBLE (-1550 1950);
FORCEPROP 1 LAST SIZE 1B
J 0
(-1475 1900);
DISPLAY 0.872340 (-1475 1900);
PAINT GREEN (-1475 1900);
DISPLAY INVISIBLE (-1475 1900);
FORCEPROP 1 LAST HDL_POWER GND
J 0
(-1550 2100);
DISPLAY 0.872340 (-1550 2100);
PAINT GREEN (-1550 2100);
DISPLAY INVISIBLE (-1550 2100);
FORCEADD Q_RES..2
(-2000 2325);
FORCEPROP 1 LAST PART_NUMBER CS31742FB04
J 0
(-1960 2200);
DISPLAY 0.638298 (-1960 2200);
DISPLAY INVISIBLE (-1960 2200);
FORCEPROP 2 LAST ROOM NIC1_P12V_MPS_MAM_BOM3
J 0
(-1950 2500);
DISPLAY 1.021277 (-1950 2500);
FORCEPROP 1 LAST MATERIAL CHIP
J 0
(-1960 2250);
DISPLAY 0.638298 (-1960 2250);
FORCEPROP 1 LAST PACK_TYPE 0402LF
J 0
(-1960 2150);
DISPLAY 0.638298 (-1960 2150);
FORCEPROP 1 LAST WATTAGE 1/16W
J 0
(-1960 2300);
DISPLAY 0.638298 (-1960 2300);
FORCEPROP 1 LAST TOLERANCE 1%
J 0
(-1955 2350);
DISPLAY 0.638298 (-1955 2350);
FORCEPROP 1 LAST VALUE 17.4K
J 0
(-1955 2400);
DISPLAY 0.638298 (-1955 2400);
FORCEPROP 1 LAST LOCATION PR3849
J 0
(-1955 2450);
DISPLAY 0.638298 (-1955 2450);
FORCEPROP 1 LASTPIN (-2000 2425) $PN 1
J 0
(-1995 2387);
DISPLAY 0.787234 (-1995 2387);
PAINT MONO (-1995 2387);
FORCEPROP 1 LASTPIN (-2000 2225) $PN 2
J 0
(-1995 2235);
DISPLAY 0.787234 (-1995 2235);
PAINT MONO (-1995 2235);
FORCEPROP 2 LAST ROOM1 NIC1_P12V_MPS_TIC_BOM4
J 0
(-1950 2550);
DISPLAY 1.021277 (-1950 2550);
DISPLAY INVISIBLE (-1950 2550);
FORCEPROP 2 LAST CDS_LIB pure_quanta
J 0
(-2000 2325);
DISPLAY INVISIBLE (-2000 2325);
FORCEPROP 1 LAST PATH I72
J 0
(-1950 2500);
DISPLAY 0.978723 (-1950 2500);
PAINT WHITE (-1950 2500);
DISPLAY INVISIBLE (-1950 2500);
FORCEPROP 0 LAST $SEC 1
J 0
(-1950 2500);
DISPLAY 0.680851 (-1950 2500);
PAINT MONO (-1950 2500);
DISPLAY INVISIBLE (-1950 2500);
FORCEPROP 0 LAST CDS_SEC 1
J 0
(-1950 2500);
DISPLAY 1.021277 (-1950 2500);
DISPLAY INVISIBLE (-1950 2500);
FORCEADD Q_CAP..1
(-1550 2325);
FORCEPROP 1 LAST PART_NUMBER CH11006JB18
J 0
(-1495 2217);
DISPLAY 0.638298 (-1495 2217);
DISPLAY INVISIBLE (-1495 2217);
FORCEPROP 2 LAST ROOM NIC1_P12V_MPS_MAM_BOM3
J 0
(-1500 2475);
DISPLAY 1.021277 (-1500 2475);
FORCEPROP 1 LAST VOLTAGE 50V
J 0
(-1495 2317);
DISPLAY 0.638298 (-1495 2317);
FORCEPROP 1 LAST MATERIAL X7R
J 0
(-1500 2150);
DISPLAY 0.638298 (-1500 2150);
FORCEPROP 1 LAST PACK_TYPE 0402
J 0
(-1495 2267);
DISPLAY 0.638298 (-1495 2267);
FORCEPROP 1 LAST VALUE 100PF
J 0
(-1500 2375);
DISPLAY 0.638298 (-1500 2375);
FORCEPROP 1 LAST LOCATION PC2167
J 0
(-1500 2425);
DISPLAY 0.787234 (-1500 2425);
FORCEPROP 2 LAST ROOM1 NIC1_P12V_MPS_TIC_BOM4
J 0
(-1500 2525);
DISPLAY 1.021277 (-1500 2525);
DISPLAY INVISIBLE (-1500 2525);
FORCEPROP 2 LAST CDS_LIB pure_quanta
J 0
(-1550 2325);
DISPLAY INVISIBLE (-1550 2325);
FORCEPROP 1 LAST TOLERANCE 5%
J 0
(-1500 2275);
DISPLAY 0.638298 (-1500 2275);
DISPLAY INVISIBLE (-1500 2275);
FORCEPROP 1 LAST PATH I73
J 0
(-1500 2475);
DISPLAY 0.978723 (-1500 2475);
PAINT WHITE (-1500 2475);
DISPLAY INVISIBLE (-1500 2475);
FORCEPROP 0 LAST $SEC 1
J 0
(-1500 2475);
DISPLAY INVISIBLE (-1500 2475);
FORCEPROP 0 LAST CDS_SEC 1
J 0
(-1500 2475);
DISPLAY INVISIBLE (-1500 2475);
FORCEPROP 1 LASTPIN (-1550 2425) $PN 1
J 0
(-1540 2405);
DISPLAY 0.787234 (-1540 2405);
PAINT MONO (-1540 2405);
DISPLAY INVISIBLE (-1540 2405);
FORCEPROP 1 LASTPIN (-1550 2225) $PN 2
J 0
(-1540 2205);
DISPLAY 0.787234 (-1540 2205);
PAINT MONO (-1540 2205);
DISPLAY INVISIBLE (-1540 2205);
FORCEADD Q_RES..1
(-1425 2675);
FORCEPROP 1 LAST PART_NUMBER CS31002FB08
J 0
(-1550 2700);
DISPLAY 0.510638 (-1550 2700);
DISPLAY INVISIBLE (-1550 2700);
FORCEPROP 2 LAST ROOM NIC1_P12V_MPS_MAM_BOM3
J 0
(-1500 2775);
DISPLAY 1.021277 (-1500 2775);
FORCEPROP 1 LAST TOLERANCE 1%
J 0
(-1400 2625);
DISPLAY 0.510638 (-1400 2625);
FORCEPROP 1 LAST VALUE 10K
J 2
(-1425 2625);
DISPLAY 0.510638 (-1425 2625);
FORCEPROP 1 LAST WATTAGE 1/16W
J 2
(-1425 2600);
DISPLAY 0.510638 (-1425 2600);
FORCEPROP 1 LAST PACK_TYPE 0402LF
J 0
(-1300 2625);
DISPLAY 0.510638 (-1300 2625);
FORCEPROP 1 LAST MATERIAL CHIP
J 0
(-1400 2600);
DISPLAY 0.510638 (-1400 2600);
FORCEPROP 1 LAST LOCATION PR3851
J 0
(-1500 2725);
DISPLAY 0.638298 (-1500 2725);
FORCEPROP 2 LAST ROOM1 NIC1_P12V_MPS_TIC_BOM4
J 0
(-1500 2825);
DISPLAY 1.021277 (-1500 2825);
DISPLAY INVISIBLE (-1500 2825);
FORCEPROP 2 LAST CDS_LIB pure_quanta
J 0
(-1425 2675);
DISPLAY INVISIBLE (-1425 2675);
FORCEPROP 1 LAST PATH I74
J 0
(-1475 2825);
DISPLAY 0.978723 (-1475 2825);
PAINT WHITE (-1475 2825);
DISPLAY INVISIBLE (-1475 2825);
FORCEPROP 0 LAST $SEC 1
J 0
(-1550 2725);
DISPLAY 0.680851 (-1550 2725);
PAINT MONO (-1550 2725);
DISPLAY INVISIBLE (-1550 2725);
FORCEPROP 0 LAST CDS_SEC 1
J 0
(-1725 2800);
DISPLAY INVISIBLE (-1725 2800);
FORCEPROP 1 LASTPIN (-1525 2675) $PN 1
J 0
(-1513 2687);
DISPLAY 0.787234 (-1513 2687);
PAINT MONO (-1513 2687);
DISPLAY INVISIBLE (-1513 2687);
FORCEPROP 1 LASTPIN (-1325 2675) $PN 2
J 0
(-1363 2687);
DISPLAY 0.787234 (-1363 2687);
PAINT MONO (-1363 2687);
DISPLAY INVISIBLE (-1363 2687);
FORCEADD Q_RES..2
(-2050 3725);
FORCEPROP 1 LAST PART_NUMBER CS31002FB08
J 0
(-2005 3650);
DISPLAY 0.510638 (-2005 3650);
DISPLAY INVISIBLE (-2005 3650);
FORCEPROP 2 LAST ROOM NIC1_P12V_MPS_MAM_BOM3
J 0
(-2000 3925);
DISPLAY 1.021277 (-2000 3925);
FORCEPROP 1 LAST PACK_TYPE 0402LF
J 0
(-2005 3600);
DISPLAY 0.510638 (-2005 3600);
FORCEPROP 1 LAST VALUE 10K
J 0
(-2000 3850);
DISPLAY 0.510638 (-2000 3850);
FORCEPROP 1 LAST TOLERANCE 1%
J 0
(-2000 3800);
DISPLAY 0.510638 (-2000 3800);
FORCEPROP 1 LAST WATTAGE 1/16W
J 0
(-2005 3750);
DISPLAY 0.510638 (-2005 3750);
FORCEPROP 1 LAST MATERIAL CHIP
J 0
(-2005 3700);
DISPLAY 0.510638 (-2005 3700);
FORCEPROP 1 LAST $LOCATION R3848
J 0
(-2000 3900);
DISPLAY 0.510638 (-2000 3900);
FORCEPROP 1 LASTPIN (-2050 3825) $PN 1
J 0
(-2045 3787);
DISPLAY 0.787234 (-2045 3787);
PAINT MONO (-2045 3787);
FORCEPROP 1 LASTPIN (-2050 3625) $PN 2
J 0
(-2045 3635);
DISPLAY 0.787234 (-2045 3635);
PAINT MONO (-2045 3635);
FORCEPROP 2 LAST ROOM1 NIC1_P12V_MPS_TIC_BOM4
J 0
(-2000 3975);
DISPLAY 1.021277 (-2000 3975);
DISPLAY INVISIBLE (-2000 3975);
FORCEPROP 2 LAST CDS_LIB pure_quanta
J 0
(-2050 3725);
DISPLAY INVISIBLE (-2050 3725);
FORCEPROP 1 LAST PATH I75
J 0
(-2000 3900);
DISPLAY 0.978723 (-2000 3900);
PAINT WHITE (-2000 3900);
DISPLAY INVISIBLE (-2000 3900);
FORCEPROP 0 LAST CDS_LOCATION R3848
J 0
(-2000 3925);
DISPLAY 1.021277 (-2000 3925);
DISPLAY INVISIBLE (-2000 3925);
FORCEPROP 0 LAST $SEC 1
J 0
(-2000 3925);
DISPLAY 0.680851 (-2000 3925);
PAINT MONO (-2000 3925);
DISPLAY INVISIBLE (-2000 3925);
FORCEPROP 0 LAST CDS_SEC 1
J 0
(-2000 3875);
DISPLAY INVISIBLE (-2000 3875);
FORCEADD VCCAUX15..1
(-2050 3950);
FORCEPROP 3 LASTPIN (-2050 3900) SIG_NAME P3V3_AUX\g
J 0
(-2040 3910);
DISPLAY 0.659574 (-2040 3910);
PAINT MONO (-2040 3910);
DISPLAY INVISIBLE (-2040 3910);
FORCEPROP 1 LAST HDL_POWER P3V3_AUX
J 1
(-2050 4000);
DISPLAY 0.723404 (-2050 4000);
PAINT GREEN (-2050 4000);
FORCEPROP 1 LAST PATH I76
J 0
(-2000 3975);
DISPLAY 0.872340 (-2000 3975);
PAINT AQUA (-2000 3975);
DISPLAY INVISIBLE (-2000 3975);
FORCEPROP 2 LAST CDS_LIB logical_power
J 0
(-2050 3950);
DISPLAY INVISIBLE (-2050 3950);
FORCEADD Q_RES..2
(-1500 3150);
FORCEPROP 1 LAST PART_NUMBER CS11002FB07
J 0
(-1460 2975);
DISPLAY 0.510638 (-1460 2975);
DISPLAY INVISIBLE (-1460 2975);
FORCEPROP 1 LAST PACK_TYPE 0402LF
J 0
(-1460 3025);
DISPLAY 0.510638 (-1460 3025);
FORCEPROP 1 LAST VALUE 100
J 0
(-1455 3225);
DISPLAY 0.510638 (-1455 3225);
FORCEPROP 1 LAST TOLERANCE 1%
J 0
(-1455 3175);
DISPLAY 0.510638 (-1455 3175);
FORCEPROP 1 LAST WATTAGE 1/16W
J 0
(-1460 3125);
DISPLAY 0.510638 (-1460 3125);
FORCEPROP 1 LAST MATERIAL EMPTY
J 0
(-1460 3075);
DISPLAY 0.510638 (-1460 3075);
PAINT RED (-1460 3075);
FORCEPROP 1 LAST LOCATION PR3850
J 0
(-1455 3275);
DISPLAY 0.978723 (-1455 3275);
FORCEPROP 1 LASTPIN (-1500 3250) $PN 1
J 0
(-1495 3212);
DISPLAY 0.787234 (-1495 3212);
PAINT MONO (-1495 3212);
FORCEPROP 1 LASTPIN (-1500 3050) $PN 2
J 0
(-1495 3060);
DISPLAY 0.787234 (-1495 3060);
PAINT MONO (-1495 3060);
FORCEPROP 1 LAST PATH I77
J 0
(-1450 3325);
DISPLAY 0.978723 (-1450 3325);
PAINT WHITE (-1450 3325);
DISPLAY INVISIBLE (-1450 3325);
FORCEPROP 2 LAST CDS_LIB pure_quanta
J 0
(-1500 3150);
DISPLAY INVISIBLE (-1500 3150);
FORCEPROP 0 LAST $SEC 1
J 0
(-1450 3325);
DISPLAY 0.680851 (-1450 3325);
PAINT MONO (-1450 3325);
DISPLAY INVISIBLE (-1450 3325);
FORCEPROP 0 LAST CDS_SEC 1
J 0
(-1450 3325);
DISPLAY 1.021277 (-1450 3325);
DISPLAY INVISIBLE (-1450 3325);
FORCEADD OFFPAGE..2
(-1250 3525);
PAINT AQUA (-1250 3525);
FORCEPROP 2 LAST $XR1 164 
J 0
(-941 3525);
DISPLAY 0.638298 (-941 3525);
PAINT MONO (-941 3525);
FORCEPROP 2 LAST $XR0 162 
J 0
(-1061 3525);
DISPLAY 0.638298 (-1061 3525);
PAINT MONO (-1061 3525);
FORCEPROP 2 LAST $XR2 214 
J 0
(-821 3525);
DISPLAY 0.638298 (-821 3525);
PAINT MONO (-821 3525);
FORCEPROP 2 LAST PATH I78
J 0
(-925 3575);
DISPLAY 1.021277 (-925 3575);
DISPLAY INVISIBLE (-925 3575);
FORCEPROP 2 LAST CDS_LIB standard
J 0
(-1250 3525);
DISPLAY INVISIBLE (-1250 3525);
FORCEPROP 1 LAST OFFPAGE TRUE
J 0
(-925 3400);
DISPLAY 0.872340 (-925 3400);
PAINT AQUA (-925 3400);
DISPLAY INVISIBLE (-925 3400);
FORCEPROP 1 LAST COMMENT_BODY TRUE
J 0
(-1295 3430);
DISPLAY 0.872340 (-1295 3430);
PAINT GREEN (-1295 3430);
DISPLAY INVISIBLE (-1295 3430);
FORCEADD VCCAUX15..1
(-1155 2733);
FORCEPROP 3 LASTPIN (-1155 2683) SIG_NAME P3V3_AUX\g
J 0
(-1145 2693);
DISPLAY 0.659574 (-1145 2693);
PAINT MONO (-1145 2693);
DISPLAY INVISIBLE (-1145 2693);
FORCEPROP 1 LAST HDL_POWER P3V3_AUX
J 1
(-1125 2775);
DISPLAY 0.723404 (-1125 2775);
PAINT GREEN (-1125 2775);
FORCEPROP 1 LAST PATH I79
J 0
(-1105 2758);
DISPLAY 0.872340 (-1105 2758);
PAINT AQUA (-1105 2758);
DISPLAY INVISIBLE (-1105 2758);
FORCEPROP 2 LAST CDS_LIB logical_power
J 0
(-1155 2733);
DISPLAY INVISIBLE (-1155 2733);
FORCEADD Q_RES..1
(-150 2075);
FORCEPROP 1 LAST PART_NUMBER CS00002JB13
J 0
(-325 2025);
DISPLAY 0.595745 (-325 2025);
DISPLAY INVISIBLE (-325 2025);
FORCEPROP 2 LAST ROOM1 NIC1_P12V_MPS_TIC_BOM4
J 0
(-500 1900);
DISPLAY 1.021277 (-500 1900);
FORCEPROP 1 LAST VALUE 0
J 2
(0 2075);
DISPLAY 0.595745 (0 2075);
FORCEPROP 1 LAST MATERIAL CHIP
J 0
(-375 2075);
DISPLAY 0.595745 (-375 2075);
FORCEPROP 1 LAST PACK_TYPE 0402LF
J 0
(0 2025);
DISPLAY 0.595745 (0 2025);
FORCEPROP 1 LAST TOLERANCE 5%
J 0
(25 2075);
DISPLAY 0.595745 (25 2075);
FORCEPROP 1 LAST WATTAGE 1/16W
J 2
(-350 2025);
DISPLAY 0.595745 (-350 2025);
FORCEPROP 1 LAST $LOCATION R3874
J 0
(-500 2100);
DISPLAY 0.978723 (-500 2100);
FORCEPROP 1 LASTPIN (-250 2075) $PN 1
J 0
(-238 2087);
DISPLAY 0.787234 (-238 2087);
PAINT MONO (-238 2087);
FORCEPROP 1 LASTPIN (-50 2075) $PN 2
J 0
(-88 2087);
DISPLAY 0.787234 (-88 2087);
PAINT MONO (-88 2087);
FORCEPROP 1 LAST PATH I80
J 0
(-200 2225);
DISPLAY 0.978723 (-200 2225);
PAINT WHITE (-200 2225);
DISPLAY INVISIBLE (-200 2225);
FORCEPROP 2 LAST CDS_LIB pure_quanta
J 0
(-150 2075);
DISPLAY INVISIBLE (-150 2075);
FORCEPROP 0 LAST CDS_LOCATION R3874
J 0
(-200 2175);
DISPLAY 1.021277 (-200 2175);
DISPLAY INVISIBLE (-200 2175);
FORCEPROP 0 LAST $SEC 1
J 0
(-200 2175);
DISPLAY 0.680851 (-200 2175);
PAINT MONO (-200 2175);
DISPLAY INVISIBLE (-200 2175);
FORCEPROP 0 LAST CDS_SEC 1
J 0
(-200 2175);
DISPLAY 1.021277 (-200 2175);
DISPLAY INVISIBLE (-200 2175);
FORCEADD Q_RES..1
(-150 2200);
FORCEPROP 1 LAST PART_NUMBER CS00002JB13
J 0
(-325 2150);
DISPLAY 0.595745 (-325 2150);
DISPLAY INVISIBLE (-325 2150);
FORCEPROP 2 LAST ROOM NIC1_P12V_MPS_MAM_BOM3
J 0
(-500 2300);
DISPLAY 1.021277 (-500 2300);
FORCEPROP 1 LAST TOLERANCE 5%
J 0
(25 2200);
DISPLAY 0.595745 (25 2200);
FORCEPROP 1 LAST VALUE 0
J 2
(0 2200);
DISPLAY 0.595745 (0 2200);
FORCEPROP 1 LAST WATTAGE 1/16W
J 2
(-350 2150);
DISPLAY 0.595745 (-350 2150);
FORCEPROP 1 LAST MATERIAL EMPTY
J 0
(-375 2200);
DISPLAY 0.595745 (-375 2200);
PAINT RED (-375 2200);
FORCEPROP 1 LAST PACK_TYPE 0402LF
J 0
(0 2150);
DISPLAY 0.595745 (0 2150);
FORCEPROP 1 LAST $LOCATION R3873
J 0
(-500 2250);
DISPLAY 0.978723 (-500 2250);
FORCEPROP 1 LASTPIN (-250 2200) $PN 1
J 0
(-238 2212);
DISPLAY 0.787234 (-238 2212);
PAINT MONO (-238 2212);
FORCEPROP 1 LASTPIN (-50 2200) $PN 2
J 0
(-88 2212);
DISPLAY 0.787234 (-88 2212);
PAINT MONO (-88 2212);
FORCEPROP 2 LAST CDS_LIB pure_quanta
J 0
(-150 2200);
DISPLAY INVISIBLE (-150 2200);
FORCEPROP 1 LAST PATH I81
J 0
(-200 2350);
DISPLAY 0.978723 (-200 2350);
PAINT WHITE (-200 2350);
DISPLAY INVISIBLE (-200 2350);
FORCEPROP 0 LAST CDS_LOCATION R3873
J 0
(-200 2300);
DISPLAY 1.021277 (-200 2300);
DISPLAY INVISIBLE (-200 2300);
FORCEPROP 0 LAST $SEC 1
J 0
(-200 2300);
DISPLAY 0.680851 (-200 2300);
PAINT MONO (-200 2300);
DISPLAY INVISIBLE (-200 2300);
FORCEPROP 0 LAST CDS_SEC 1
J 0
(-200 2300);
DISPLAY 1.021277 (-200 2300);
DISPLAY INVISIBLE (-200 2300);
FORCEADD GND..1
(-355 2333);
FORCEPROP 3 LASTPIN (-355 2383) SIG_NAME GND\g
J 0
(-345 2393);
DISPLAY 0.659574 (-345 2393);
PAINT MONO (-345 2393);
DISPLAY INVISIBLE (-345 2393);
FORCEPROP 1 LAST PATH I82
J 0
(-280 2333);
DISPLAY 0.872340 (-280 2333);
PAINT AQUA (-280 2333);
DISPLAY INVISIBLE (-280 2333);
FORCEPROP 2 LAST CDS_LIB logical_power
J 0
(-355 2333);
DISPLAY INVISIBLE (-355 2333);
FORCEPROP 1 LAST SIZE 1B
J 0
(-280 2283);
DISPLAY 0.872340 (-280 2283);
PAINT GREEN (-280 2283);
DISPLAY INVISIBLE (-280 2283);
FORCEPROP 1 LAST HDL_POWER GND
J 0
(-355 2483);
DISPLAY 0.872340 (-355 2483);
PAINT GREEN (-355 2483);
DISPLAY INVISIBLE (-355 2483);
FORCEADD Q_RES..2
(-555 2658);
FORCEPROP 1 LAST PART_NUMBER CS31002FB08
J 0
(-515 2533);
DISPLAY 0.638298 (-515 2533);
DISPLAY INVISIBLE (-515 2533);
FORCEPROP 2 LAST ROOM NIC1_P12V_MPS_MAM_BOM3
J 0
(-500 2825);
DISPLAY 1.021277 (-500 2825);
FORCEPROP 1 LAST WATTAGE 1/16W
J 0
(-515 2633);
DISPLAY 0.638298 (-515 2633);
FORCEPROP 1 LAST PACK_TYPE 0402LF
J 0
(-515 2483);
DISPLAY 0.638298 (-515 2483);
FORCEPROP 1 LAST VALUE 10K
J 0
(-510 2733);
DISPLAY 0.638298 (-510 2733);
FORCEPROP 1 LAST MATERIAL CHIP
J 0
(-515 2583);
DISPLAY 0.638298 (-515 2583);
FORCEPROP 1 LAST TOLERANCE 1%
J 0
(-510 2683);
DISPLAY 0.638298 (-510 2683);
FORCEPROP 1 LAST LOCATION PR3854
J 0
(-510 2783);
DISPLAY 0.638298 (-510 2783);
FORCEPROP 2 LAST ROOM1 NIC1_P12V_MPS_TIC_BOM4
J 0
(-500 2875);
DISPLAY 1.021277 (-500 2875);
DISPLAY INVISIBLE (-500 2875);
FORCEPROP 2 LAST CDS_LIB pure_quanta
J 0
(-555 2658);
DISPLAY INVISIBLE (-555 2658);
FORCEPROP 1 LAST PATH I83
J 0
(-505 2833);
DISPLAY 0.978723 (-505 2833);
PAINT WHITE (-505 2833);
DISPLAY INVISIBLE (-505 2833);
FORCEPROP 0 LAST $SEC 1
J 0
(-505 2833);
DISPLAY INVISIBLE (-505 2833);
FORCEPROP 0 LAST CDS_SEC 1
J 0
(-505 2833);
DISPLAY INVISIBLE (-505 2833);
FORCEPROP 1 LASTPIN (-555 2758) $PN 1
J 0
(-550 2720);
DISPLAY 0.787234 (-550 2720);
PAINT MONO (-550 2720);
DISPLAY INVISIBLE (-550 2720);
FORCEPROP 1 LASTPIN (-555 2558) $PN 2
J 0
(-550 2568);
DISPLAY 0.787234 (-550 2568);
PAINT MONO (-550 2568);
DISPLAY INVISIBLE (-550 2568);
FORCEADD Q_RES..2
(-555 3083);
FORCEPROP 1 LAST PART_NUMBER CS41202FB05
J 0
(-515 2958);
DISPLAY 0.638298 (-515 2958);
DISPLAY INVISIBLE (-515 2958);
FORCEPROP 2 LAST ROOM NIC1_P12V_MPS_MAM_BOM3
J 0
(-500 3250);
DISPLAY 1.021277 (-500 3250);
FORCEPROP 1 LAST WATTAGE 1/16W
J 0
(-515 3058);
DISPLAY 0.638298 (-515 3058);
FORCEPROP 1 LAST TOLERANCE 1%
J 0
(-510 3108);
DISPLAY 0.638298 (-510 3108);
FORCEPROP 1 LAST PACK_TYPE 0402LF
J 0
(-515 2908);
DISPLAY 0.638298 (-515 2908);
FORCEPROP 1 LAST MATERIAL CHIP
J 0
(-515 3008);
DISPLAY 0.638298 (-515 3008);
FORCEPROP 1 LAST VALUE 120K
J 0
(-510 3158);
DISPLAY 0.638298 (-510 3158);
FORCEPROP 1 LAST LOCATION PR3853
J 0
(-510 3208);
DISPLAY 0.638298 (-510 3208);
FORCEPROP 2 LAST ROOM1 NIC1_P12V_MPS_TIC_BOM4
J 0
(-500 3300);
DISPLAY 1.021277 (-500 3300);
DISPLAY INVISIBLE (-500 3300);
FORCEPROP 2 LAST CDS_LIB pure_quanta
J 0
(-555 3083);
DISPLAY INVISIBLE (-555 3083);
FORCEPROP 1 LAST PATH I84
J 0
(-505 3258);
DISPLAY 0.978723 (-505 3258);
PAINT WHITE (-505 3258);
DISPLAY INVISIBLE (-505 3258);
FORCEPROP 0 LAST $SEC 1
J 0
(-505 3258);
DISPLAY INVISIBLE (-505 3258);
FORCEPROP 0 LAST CDS_SEC 1
J 0
(-505 3258);
DISPLAY INVISIBLE (-505 3258);
FORCEPROP 1 LASTPIN (-555 3183) $PN 1
J 0
(-550 3145);
DISPLAY 0.787234 (-550 3145);
PAINT MONO (-550 3145);
DISPLAY INVISIBLE (-550 3145);
FORCEPROP 1 LASTPIN (-555 2983) $PN 2
J 0
(-550 2993);
DISPLAY 0.787234 (-550 2993);
PAINT MONO (-550 2993);
DISPLAY INVISIBLE (-550 2993);
FORCEADD Q_RES..2
(-950 3150);
FORCEPROP 1 LAST PART_NUMBER CS37152FB05
J 0
(-925 3025);
DISPLAY 0.468085 (-925 3025);
PAINT WHITE (-925 3025);
DISPLAY INVISIBLE (-925 3025);
FORCEPROP 1 LAST MATERIAL EMPTY
J 0
(-925 2975);
DISPLAY 0.723404 (-925 2975);
PAINT RED (-925 2975);
FORCEPROP 1 LAST VALUE 71.5K
J 0
(-925 3175);
DISPLAY 0.574468 (-925 3175);
PAINT SKYBLUE (-925 3175);
FORCEPROP 1 LAST TOLERANCE 1%
J 0
(-925 3125);
DISPLAY 0.574468 (-925 3125);
PAINT SKYBLUE (-925 3125);
FORCEPROP 1 LAST PACK_TYPE 0402LF
J 0
(-925 3075);
DISPLAY 0.574468 (-925 3075);
PAINT SKYBLUE (-925 3075);
FORCEPROP 1 LAST LOCATION PR3852
J 0
(-925 3225);
DISPLAY 0.723404 (-925 3225);
PAINT AQUA (-925 3225);
FORCEPROP 1 LASTPIN (-950 3250) $PN 1
J 0
(-945 3212);
DISPLAY 0.787234 (-945 3212);
PAINT MONO (-945 3212);
FORCEPROP 1 LASTPIN (-950 3050) $PN 2
J 0
(-945 3060);
DISPLAY 0.787234 (-945 3060);
PAINT MONO (-945 3060);
FORCEPROP 1 LAST PATH I85
J 0
(-900 3325);
DISPLAY 0.978723 (-900 3325);
PAINT WHITE (-900 3325);
DISPLAY INVISIBLE (-900 3325);
FORCEPROP 2 LAST CDS_LIB pure_quanta
J 0
(-950 3150);
DISPLAY INVISIBLE (-950 3150);
FORCEPROP 1 LAST WATTAGE 1/16W
J 0
(-925 3125);
DISPLAY 0.723404 (-925 3125);
PAINT SKYBLUE (-925 3125);
DISPLAY INVISIBLE (-925 3125);
FORCEPROP 0 LAST $SEC 1
J 0
(-925 3275);
DISPLAY 0.680851 (-925 3275);
PAINT MONO (-925 3275);
DISPLAY INVISIBLE (-925 3275);
FORCEPROP 0 LAST CDS_SEC 1
J 0
(-925 3275);
DISPLAY 1.021277 (-925 3275);
DISPLAY INVISIBLE (-925 3275);
FORCEADD UNIVERSAL_POWER..1
(-3500 4100);
FORCEPROP 3 LASTPIN (-3500 4050) SIG_NAME P12V_AUX\g
J 0
(-3490 4060);
DISPLAY 0.659574 (-3490 4060);
PAINT MONO (-3490 4060);
DISPLAY INVISIBLE (-3490 4060);
FORCEPROP 1 LAST HDL_POWER P12V_AUX
J 1
(-3500 4150);
DISPLAY 0.872340 (-3500 4150);
PAINT GREEN (-3500 4150);
FORCEPROP 1 LAST PATH I86
J 0
(-3450 4125);
DISPLAY 0.872340 (-3450 4125);
PAINT AQUA (-3450 4125);
DISPLAY INVISIBLE (-3450 4125);
FORCEPROP 2 LAST CDS_LIB logical_power
J 0
(-3500 4100);
DISPLAY INVISIBLE (-3500 4100);
FORCEADD Q_RES..2
(-25 3075);
FORCEPROP 1 LAST PART_NUMBER CS04993F909
J 0
(15 2950);
DISPLAY 0.638298 (15 2950);
DISPLAY INVISIBLE (15 2950);
FORCEPROP 2 LAST ROOM NIC1_P12V_MPS_MAM_BOM3
J 0
(25 3250);
DISPLAY 1.021277 (25 3250);
FORCEPROP 1 LAST TOLERANCE 1%
J 0
(20 3100);
DISPLAY 0.638298 (20 3100);
FORCEPROP 1 LAST PACK_TYPE 0603LF
J 0
(15 2900);
DISPLAY 0.638298 (15 2900);
FORCEPROP 1 LAST MATERIAL CHIP
J 0
(15 3000);
DISPLAY 0.638298 (15 3000);
FORCEPROP 1 LAST WATTAGE 1/10W
J 0
(15 3050);
DISPLAY 0.638298 (15 3050);
FORCEPROP 1 LAST VALUE 49.9
J 0
(20 3150);
DISPLAY 0.638298 (20 3150);
FORCEPROP 1 LAST LOCATION PR3857
J 0
(20 3200);
DISPLAY 0.638298 (20 3200);
FORCEPROP 1 LASTPIN (-25 3175) $PN 1
J 0
(-20 3137);
DISPLAY 0.787234 (-20 3137);
PAINT MONO (-20 3137);
FORCEPROP 1 LASTPIN (-25 2975) $PN 2
J 0
(-20 2985);
DISPLAY 0.787234 (-20 2985);
PAINT MONO (-20 2985);
FORCEPROP 2 LAST ROOM1 NIC1_P12V_MPS_TIC_BOM4
J 0
(25 3300);
DISPLAY 1.021277 (25 3300);
DISPLAY INVISIBLE (25 3300);
FORCEPROP 2 LAST CDS_LIB pure_quanta
J 0
(-25 3075);
DISPLAY INVISIBLE (-25 3075);
FORCEPROP 1 LAST PATH I87
J 0
(25 3250);
DISPLAY 0.978723 (25 3250);
PAINT WHITE (25 3250);
DISPLAY INVISIBLE (25 3250);
FORCEPROP 0 LAST $SEC 1
J 0
(30 3242);
DISPLAY 0.680851 (30 3242);
PAINT MONO (30 3242);
DISPLAY INVISIBLE (30 3242);
FORCEPROP 0 LAST CDS_SEC 1
J 0
(30 3242);
DISPLAY 1.021277 (30 3242);
DISPLAY INVISIBLE (30 3242);
FORCEADD OFFPAGE..2
(900 2825);
PAINT AQUA (900 2825);
FORCEPROP 2 LAST $XR0 163 
J 0
(1089 2825);
DISPLAY 0.638298 (1089 2825);
PAINT MONO (1089 2825);
FORCEPROP 2 LAST PATH I88
J 0
(1100 2875);
DISPLAY 1.021277 (1100 2875);
DISPLAY INVISIBLE (1100 2875);
FORCEPROP 2 LAST CDS_LIB standard
J 0
(900 2825);
DISPLAY INVISIBLE (900 2825);
FORCEPROP 1 LAST OFFPAGE TRUE
J 0
(1225 2700);
DISPLAY 0.872340 (1225 2700);
PAINT AQUA (1225 2700);
DISPLAY INVISIBLE (1225 2700);
FORCEPROP 1 LAST COMMENT_BODY TRUE
J 0
(855 2730);
DISPLAY 0.872340 (855 2730);
PAINT GREEN (855 2730);
DISPLAY INVISIBLE (855 2730);
FORCEADD UNIVERSAL_POWER..1
(-75 3350);
FORCEPROP 3 LASTPIN (-75 3300) SIG_NAME P12V_AUX\g
J 0
(-65 3310);
DISPLAY 0.659574 (-65 3310);
PAINT MONO (-65 3310);
DISPLAY INVISIBLE (-65 3310);
FORCEPROP 1 LAST HDL_POWER P12V_AUX
J 1
(-75 3400);
DISPLAY 0.702128 (-75 3400);
PAINT GREEN (-75 3400);
FORCEPROP 1 LAST PATH I89
J 0
(-25 3375);
DISPLAY 0.872340 (-25 3375);
PAINT AQUA (-25 3375);
DISPLAY INVISIBLE (-25 3375);
FORCEPROP 2 LAST CDS_LIB logical_power
J 0
(-75 3350);
DISPLAY INVISIBLE (-75 3350);
FORCEADD GND..1
(475 3075);
FORCEPROP 3 LASTPIN (475 3125) SIG_NAME GND\g
J 0
(485 3135);
DISPLAY 0.659574 (485 3135);
PAINT MONO (485 3135);
DISPLAY INVISIBLE (485 3135);
FORCEPROP 1 LAST PATH I90
J 0
(550 3075);
DISPLAY 0.872340 (550 3075);
PAINT AQUA (550 3075);
DISPLAY INVISIBLE (550 3075);
FORCEPROP 1 LAST SIZE 1B
J 0
(550 3025);
DISPLAY 0.872340 (550 3025);
PAINT GREEN (550 3025);
DISPLAY INVISIBLE (550 3025);
FORCEPROP 2 LAST CDS_LIB logical_power
J 0
(475 3075);
DISPLAY INVISIBLE (475 3075);
FORCEPROP 1 LAST HDL_POWER GND
J 0
(475 3225);
DISPLAY 0.872340 (475 3225);
PAINT GREEN (475 3225);
DISPLAY INVISIBLE (475 3225);
FORCEADD Q_CAP..1
R 2
(475 3325);
FORCEPROP 1 LAST PART_NUMBER CH4104K1B00
J 0
(525 3150);
DISPLAY 0.638298 (525 3150);
DISPLAY INVISIBLE (525 3150);
FORCEPROP 2 LAST ROOM NIC1_P12V_MPS_MAM_BOM3
J 0
(525 3500);
DISPLAY 1.021277 (525 3500);
FORCEPROP 1 LAST MATERIAL X7R
J 0
(525 3250);
DISPLAY 0.638298 (525 3250);
FORCEPROP 1 LAST PACK_TYPE 0402
J 0
(525 3200);
DISPLAY 0.638298 (525 3200);
FORCEPROP 1 LAST VALUE 0.1UF
J 0
(525 3400);
DISPLAY 0.638298 (525 3400);
FORCEPROP 1 LAST VOLTAGE 25V
J 0
(525 3350);
DISPLAY 0.638298 (525 3350);
FORCEPROP 1 LAST TOLERANCE 10%
J 0
(525 3300);
DISPLAY 0.638298 (525 3300);
FORCEPROP 1 LAST LOCATION PC2174
J 0
(525 3450);
DISPLAY 0.638298 (525 3450);
FORCEPROP 1 LASTPIN (475 3425) $PN 1
J 2
(465 3405);
DISPLAY 0.787234 (465 3405);
PAINT MONO (465 3405);
FORCEPROP 1 LASTPIN (475 3225) $PN 2
J 2
(465 3205);
DISPLAY 0.787234 (465 3205);
PAINT MONO (465 3205);
FORCEPROP 2 LAST ROOM1 NIC1_P12V_MPS_TIC_BOM4
J 0
(525 3550);
DISPLAY 1.021277 (525 3550);
DISPLAY INVISIBLE (525 3550);
FORCEPROP 2 LAST CDS_LIB pure_quanta
J 0
(475 3325);
DISPLAY INVISIBLE (475 3325);
FORCEPROP 1 LAST PATH I91
J 2
(425 3475);
DISPLAY 0.978723 (425 3475);
PAINT WHITE (425 3475);
DISPLAY INVISIBLE (425 3475);
FORCEPROP 0 LAST $SEC 1
J 0
(525 3500);
DISPLAY 0.680851 (525 3500);
PAINT MONO (525 3500);
DISPLAY INVISIBLE (525 3500);
FORCEPROP 0 LAST CDS_SEC 1
J 0
(525 3500);
DISPLAY 1.021277 (525 3500);
DISPLAY INVISIBLE (525 3500);
FORCEADD UNIVERSAL_POWER..1
R 2
(475 3625);
FORCEPROP 3 LASTPIN (475 3575) SIG_NAME P12V_OCP_V3_2\g
J 0
(485 3585);
DISPLAY 0.659574 (485 3585);
PAINT MONO (485 3585);
DISPLAY INVISIBLE (485 3585);
FORCEPROP 1 LAST HDL_POWER P12V_OCP_V3_2
J 1
(500 3675);
DISPLAY 0.723404 (500 3675);
PAINT GREEN (500 3675);
FORCEPROP 1 LAST PATH I92
J 2
(425 3650);
DISPLAY 0.872340 (425 3650);
PAINT AQUA (425 3650);
DISPLAY INVISIBLE (425 3650);
FORCEPROP 2 LAST CDS_LIB logical_power
J 0
(475 3625);
DISPLAY INVISIBLE (475 3625);
FORCEADD OFFPAGE..2
(1100 2075);
PAINT AQUA (1100 2075);
FORCEPROP 2 LAST $XR0 250 
J 0
(1289 2075);
DISPLAY 0.638298 (1289 2075);
PAINT MONO (1289 2075);
FORCEPROP 2 LAST PATH I93
J 0
(1300 2125);
DISPLAY 1.021277 (1300 2125);
DISPLAY INVISIBLE (1300 2125);
FORCEPROP 2 LAST CDS_LIB standard
J 0
(1100 2075);
DISPLAY INVISIBLE (1100 2075);
FORCEPROP 1 LAST OFFPAGE TRUE
J 0
(1425 1950);
DISPLAY 0.872340 (1425 1950);
PAINT AQUA (1425 1950);
DISPLAY INVISIBLE (1425 1950);
FORCEPROP 1 LAST COMMENT_BODY TRUE
J 0
(1055 1980);
DISPLAY 0.872340 (1055 1980);
PAINT GREEN (1055 1980);
DISPLAY INVISIBLE (1055 1980);
FORCEADD OFFPAGE..2
(1100 2200);
PAINT AQUA (1100 2200);
FORCEPROP 2 LAST $XR0 250 
J 0
(1289 2200);
DISPLAY 0.638298 (1289 2200);
PAINT MONO (1289 2200);
FORCEPROP 2 LAST PATH I94
J 0
(1300 2250);
DISPLAY 1.021277 (1300 2250);
DISPLAY INVISIBLE (1300 2250);
FORCEPROP 2 LAST CDS_LIB standard
J 0
(1100 2200);
DISPLAY INVISIBLE (1100 2200);
FORCEPROP 1 LAST OFFPAGE TRUE
J 0
(1425 2075);
DISPLAY 0.872340 (1425 2075);
PAINT AQUA (1425 2075);
DISPLAY INVISIBLE (1425 2075);
FORCEPROP 1 LAST COMMENT_BODY TRUE
J 0
(1055 2105);
DISPLAY 0.872340 (1055 2105);
PAINT GREEN (1055 2105);
DISPLAY INVISIBLE (1055 2105);
FORCEADD Q_CAP..1
(-25 2650);
FORCEPROP 1 LAST PART_NUMBER CH5223M1900
J 0
(25 2500);
DISPLAY 0.638298 (25 2500);
DISPLAY INVISIBLE (25 2500);
FORCEPROP 2 LAST ROOM NIC1_P12V_MPS_MAM_BOM3
J 0
(25 2800);
DISPLAY 1.021277 (25 2800);
FORCEPROP 1 LAST VOLTAGE 16V
J 0
(25 2650);
DISPLAY 0.638298 (25 2650);
FORCEPROP 1 LAST VALUE 2.2UF
J 0
(25 2700);
DISPLAY 0.638298 (25 2700);
FORCEPROP 1 LAST MATERIAL X7R
J 0
(25 2550);
DISPLAY 0.638298 (25 2550);
FORCEPROP 1 LAST PACK_TYPE C0603
J 0
(25 2450);
DISPLAY 0.638298 (25 2450);
FORCEPROP 1 LAST TOLERANCE 20%
J 0
(25 2600);
DISPLAY 0.638298 (25 2600);
FORCEPROP 1 LAST LOCATION PC1320
J 0
(25 2750);
DISPLAY 0.638298 (25 2750);
FORCEPROP 2 LAST ROOM1 NIC1_P12V_MPS_TIC_BOM4
J 0
(25 2850);
DISPLAY 1.021277 (25 2850);
DISPLAY INVISIBLE (25 2850);
FORCEPROP 2 LAST CDS_LIB pure_quanta
J 0
(-25 2650);
DISPLAY INVISIBLE (-25 2650);
FORCEPROP 1 LAST PATH I95
J 0
(25 2800);
DISPLAY 0.978723 (25 2800);
PAINT WHITE (25 2800);
DISPLAY INVISIBLE (25 2800);
FORCEPROP 0 LAST $SEC 1
J 0
(25 2800);
DISPLAY INVISIBLE (25 2800);
FORCEPROP 0 LAST CDS_SEC 1
J 0
(25 2800);
DISPLAY INVISIBLE (25 2800);
FORCEPROP 1 LASTPIN (-25 2750) $PN 1
J 0
(-15 2730);
DISPLAY 0.787234 (-15 2730);
PAINT MONO (-15 2730);
DISPLAY INVISIBLE (-15 2730);
FORCEPROP 1 LASTPIN (-25 2550) $PN 2
J 0
(-15 2530);
DISPLAY 0.787234 (-15 2530);
PAINT MONO (-15 2530);
DISPLAY INVISIBLE (-15 2530);
FORCEADD OFFPAGE..1
R 2
(-1350 2925);
PAINT AQUA (-1350 2925);
FORCEPROP 2 LAST $XR0 163 
J 0
(-1164 2925);
DISPLAY 0.638298 (-1164 2925);
PAINT MONO (-1164 2925);
FORCEPROP 2 LAST PATH I96
J 0
(-1150 2975);
DISPLAY 1.021277 (-1150 2975);
DISPLAY INVISIBLE (-1150 2975);
FORCEPROP 2 LAST CDS_LIB standard
J 2
(-1350 2925);
DISPLAY INVISIBLE (-1350 2925);
FORCEPROP 1 LAST OFFPAGE TRUE
J 2
(-1675 2800);
DISPLAY 0.872340 (-1675 2800);
PAINT AQUA (-1675 2800);
DISPLAY INVISIBLE (-1675 2800);
FORCEPROP 1 LAST COMMENT_BODY TRUE
J 2
(-1475 2825);
DISPLAY 0.872340 (-1475 2825);
PAINT GREEN (-1475 2825);
DISPLAY INVISIBLE (-1475 2825);
FORCEADD QUANTA_TITLE_BLOCK_C..1
(3575 1425);
FORCEPROP 0 LAST CDS_CON_LAST_MODIFIED Fri Aug 25 14:02:33 2023
J 0
(1690 1440);
DISPLAY INVISIBLE (1690 1440);
FORCEPROP 2 LAST CUSTOM_TXT_CDS <XR_PAGE_TITLE>
J 0
(-4315 6675);
DISPLAY 0.638298 (-4315 6675);
PAINT PINK (-4315 6675);
DISPLAY INVISIBLE (-4315 6675);
FORCEPROP 2 LAST CUSTOM_TXT_CDS <CON_LAST_MODIFIED>
J 0
(1690 1440);
DISPLAY 0.978723 (1690 1440);
FORCEPROP 2 LAST CUSTOM_TXT_CDS <Q_NUMBER>
J 0
(2172 1528);
DISPLAY 1.212766 (2172 1528);
FORCEPROP 2 LAST CUSTOM_TXT_CDS <Q_REV>
J 0
(3391 1528);
DISPLAY 1.212766 (3391 1528);
FORCEPROP 2 LAST CUSTOM_TXT_CDS <CON_PAGE_NUM> OF <CON_TOTAL_PAGES>
J 0
(3129 1443);
DISPLAY 0.978723 (3129 1443);
FORCEPROP 2 LAST CUSTOM_TXT_CDS <Q_PROJ>
J 0
(1193 1527);
DISPLAY 1.212766 (1193 1527);
FORCEPROP 2 LAST CUSTOM_TXT_CDS <NAME_2>
J 0
(400 1475);
FORCEPROP 2 LAST CUSTOM_TXT_CDS <NAME_1>
J 0
(400 1600);
FORCEPROP 1 LAST Q_TITLE V3_2_OCP3.0 HSC-CO-LAYOUT(2/3)
J 0
(-5741 1476);
DISPLAY 2.446809 (-5741 1476);
PAINT GREEN (-5741 1476);
FORCEPROP 1 LAST Q_DEPT 
J 1
(-188 1474);
DISPLAY 1.957447 (-188 1474);
PAINT GREEN (-188 1474);
FORCEPROP 2 LAST CDS_LIB pure_quanta
J 0
(3575 1425);
DISPLAY INVISIBLE (3575 1425);
FORCEPROP 1 LAST CDS_LMAN_SYM_OUTLINE -9475,6775,100,-125
J 0
(3575 1425);
DISPLAY 0.468085 (3575 1425);
PAINT GREEN (3575 1425);
DISPLAY INVISIBLE (3575 1425);
FORCEPROP 2 LAST PAGE_BORDER TRUE
J 0
(-4315 6675);
DISPLAY 0.638298 (-4315 6675);
PAINT PINK (-4315 6675);
DISPLAY INVISIBLE (-4315 6675);
FORCEPROP 1 LAST COMMENT_BODY TRUE
J 0
(3587 1412);
DISPLAY 0.978723 (3587 1412);
PAINT GREEN (3587 1412);
DISPLAY INVISIBLE (3587 1412);
FORCEPROP 2 LAST CDS_XR_PAGE_TITLE CR-163 : @S9S_MB_2U_LIB.S9S_MB_2U(SCH_1):PAGE163
J 0
(-4315 6675);
DISPLAY 0.638298 (-4315 6675);
PAINT PINK (-4315 6675);
DISPLAY INVISIBLE (-4315 6675);
FORCEADD DNS..2
(-250 6150);
PAINT RED (-250 6150);
FORCEPROP 1 LAST COMMENT_BODY TRUE
R 1
J 0
(-175 5925);
DISPLAY 0.872340 (-175 5925);
PAINT GREEN (-175 5925);
DISPLAY INVISIBLE (-175 5925);
FORCEPROP 2 LAST CDS_LIB mstr_misc
J 0
(-250 6150);
DISPLAY INVISIBLE (-250 6150);
FORCEADD DNS..2
(150 6150);
PAINT RED (150 6150);
FORCEPROP 1 LAST COMMENT_BODY TRUE
R 1
J 0
(225 5925);
DISPLAY 0.872340 (225 5925);
PAINT GREEN (225 5925);
DISPLAY INVISIBLE (225 5925);
FORCEPROP 2 LAST CDS_LIB mstr_misc
J 0
(150 6150);
DISPLAY INVISIBLE (150 6150);
FORCEADD DNS..2
(225 6500);
PAINT RED (225 6500);
FORCEPROP 1 LAST COMMENT_BODY TRUE
R 1
J 0
(300 6275);
DISPLAY 0.872340 (300 6275);
PAINT GREEN (300 6275);
DISPLAY INVISIBLE (300 6275);
FORCEPROP 2 LAST CDS_LIB mstr_misc
J 0
(225 6500);
DISPLAY INVISIBLE (225 6500);
FORCEADD DNS..2
(500 6150);
PAINT RED (500 6150);
FORCEPROP 1 LAST COMMENT_BODY TRUE
R 1
J 0
(575 5925);
DISPLAY 0.872340 (575 5925);
PAINT GREEN (575 5925);
DISPLAY INVISIBLE (575 5925);
FORCEPROP 2 LAST CDS_LIB mstr_misc
J 0
(500 6150);
DISPLAY INVISIBLE (500 6150);
FORCEADD DNS..2
(475 6750);
PAINT RED (475 6750);
FORCEPROP 1 LAST COMMENT_BODY TRUE
R 1
J 0
(550 6525);
DISPLAY 0.872340 (550 6525);
PAINT GREEN (550 6525);
DISPLAY INVISIBLE (550 6525);
FORCEPROP 2 LAST CDS_LIB mstr_misc
J 0
(475 6750);
DISPLAY INVISIBLE (475 6750);
FORCEADD DNS..2
(875 6100);
PAINT RED (875 6100);
FORCEPROP 1 LAST COMMENT_BODY TRUE
R 1
J 0
(950 5875);
DISPLAY 0.872340 (950 5875);
PAINT GREEN (950 5875);
DISPLAY INVISIBLE (950 5875);
FORCEPROP 2 LAST CDS_LIB mstr_misc
J 0
(875 6100);
DISPLAY INVISIBLE (875 6100);
FORCEADD DNS..2
(1650 6500);
PAINT RED (1650 6500);
FORCEPROP 1 LAST COMMENT_BODY TRUE
R 1
J 0
(1725 6275);
DISPLAY 0.872340 (1725 6275);
PAINT GREEN (1725 6275);
DISPLAY INVISIBLE (1725 6275);
FORCEPROP 2 LAST CDS_LIB mstr_misc
J 0
(1650 6500);
DISPLAY INVISIBLE (1650 6500);
FORCEADD DNS..2
(2500 6125);
PAINT RED (2500 6125);
FORCEPROP 1 LAST COMMENT_BODY TRUE
R 1
J 0
(2575 5900);
DISPLAY 0.872340 (2575 5900);
PAINT GREEN (2575 5900);
DISPLAY INVISIBLE (2575 5900);
FORCEPROP 2 LAST CDS_LIB mstr_misc
J 0
(2500 6125);
DISPLAY INVISIBLE (2500 6125);
FORCEADD DNS..2
(2900 6325);
PAINT RED (2900 6325);
FORCEPROP 1 LAST COMMENT_BODY TRUE
R 1
J 0
(2975 6100);
DISPLAY 0.872340 (2975 6100);
PAINT GREEN (2975 6100);
DISPLAY INVISIBLE (2975 6100);
FORCEPROP 2 LAST CDS_LIB mstr_misc
J 0
(2900 6325);
DISPLAY INVISIBLE (2900 6325);
FORCEADD CAD_NOTE..1
(450 2425);
FORCEPROP 0 LAST S1 R3873/R3874 CO-LAYOUT
J 0
(325 2300);
DISPLAY 0.808511 (325 2300);
PAINT WHITE (325 2300);
FORCEPROP 2 LAST CDS_LIB logical_power
J 0
(450 2425);
DISPLAY INVISIBLE (450 2425);
FORCEPROP 1 LAST COMMENT_BODY TRUE
J 0
(475 2525);
DISPLAY 0.978723 (475 2525);
DISPLAY INVISIBLE (475 2525);
FORCEADD DNS..2
(-950 3125);
PAINT RED (-950 3125);
FORCEPROP 2 LAST CDS_LIB mstr_misc
J 0
(-950 3125);
DISPLAY INVISIBLE (-950 3125);
FORCEPROP 1 LAST COMMENT_BODY TRUE
R 1
J 0
(-875 2900);
DISPLAY 0.872340 (-875 2900);
PAINT GREEN (-875 2900);
DISPLAY INVISIBLE (-875 2900);
FORCEADD DNS..2
(-1475 3150);
PAINT RED (-1475 3150);
FORCEPROP 1 LAST COMMENT_BODY TRUE
R 1
J 0
(-1400 2925);
DISPLAY 0.872340 (-1400 2925);
PAINT GREEN (-1400 2925);
DISPLAY INVISIBLE (-1400 2925);
FORCEPROP 2 LAST CDS_LIB mstr_misc
J 0
(-1475 3150);
DISPLAY INVISIBLE (-1475 3150);
FORCEADD DNS..2
(-125 2200);
PAINT RED (-125 2200);
FORCEPROP 2 LAST CDS_LIB mstr_misc
J 0
(-125 2200);
DISPLAY INVISIBLE (-125 2200);
FORCEPROP 1 LAST COMMENT_BODY TRUE
R 1
J 0
(-50 1975);
DISPLAY 0.872340 (-50 1975);
PAINT GREEN (-50 1975);
DISPLAY INVISIBLE (-50 1975);
WIRE 16 -1 (2900 6575)(2900 6850);
WIRE 16 -1 (2900 6575)(2900 6450);
WIRE 16 -1 (2075 6575)(2900 6575);
WIRE 16 -1 (470 6958)(470 7033);
WIRE 16 -1 (470 6958)(1070 6958);
WIRE 16 -1 (470 6858)(470 6958);
WIRE 16 -1 (475 3500)(475 3575);
WIRE 16 -1 (-950 3500)(475 3500);
WIRE 16 -1 (475 3425)(475 3500);
WIRE 16 -1 (-75 3300)(-75 3258);
WIRE 16 -1 (-3500 4050)(-3500 3950);
WIRE 16 -1 (-1155 2675)(-1155 2683);
WIRE 16 -1 (-1325 2675)(-1155 2675);
WIRE 16 -1 (-2050 3900)(-2050 3825);
WIRE 16 -1 (-250 5958)(-250 5925);
WIRE 16 -1 (150 5958)(-250 5958);
WIRE 16 -1 (-250 5958)(-250 6075);
WIRE 16 -1 (495 6058)(495 5933);
WIRE 16 -1 (470 6658)(470 6583);
WIRE 16 -1 (870 6008)(870 5933);
WIRE 16 -1 (2500 5975)(2500 5850);
WIRE 16 -1 (2225 5975)(2500 5975);
WIRE 16 -1 (2500 6050)(2500 5975);
WIRE 16 -1 (2900 6050)(2900 6250);
WIRE 16 -1 (475 3225)(475 3125);
WIRE 16 -1 (-355 2408)(-355 2383);
WIRE 16 -1 (-555 2408)(-355 2408);
WIRE 16 -1 (-355 2408)(-25 2408);
WIRE 16 -1 (-1550 2075)(-1550 2000);
WIRE 16 -1 (-2000 2075)(-1550 2075);
WIRE 16 -1 (-1550 2075)(-1550 2225);
WIRE 16 -1 (-3009 2491)(-3009 2575);
WIRE 16 -1 (-3500 3350)(-3500 3575);
WIRE 16 -1 (-3330 2308)(-3330 2408);
WIRE 16 -1 (-3300 2975)(-3775 2975);
WIRE 16 -1 (-3300 3075)(-3300 2975);
WIRE 16 -1 (-3300 2975)(-2950 2975);
WIRE 16 -1 (-3750 2350)(-3750 2475);
WIRE 16 -1 (-4175 2425)(-4175 2625);
WIRE 16 3135 (-2755 4758)(-1505 4758);
WIRE 16 3135 (-1505 4108)(-1505 4758);
WIRE 16 3135 (-2755 4108)(-2755 4758);
WIRE 16 3135 (-2755 4108)(-1505 4108);
WIRE 16 3135 (-2730 4208)(-1530 4208);
WIRE 16 3135 (-2730 4408)(-1530 4408);
WIRE 16 3135 (-2730 4608)(-1530 4608);
WIRE 16 3135 (-2730 4508)(-1530 4508);
WIRE 16 -1 (150 6075)(150 5958);
WIRE 16 -1 (1070 6575)(1275 6575);
WIRE 16 -1 (1070 6958)(1070 6575);
WIRE 16 -1 (2225 6275)(2225 5975);
WIRE 16 -1 (2225 6275)(2075 6275);
WIRE 16 -1 (-2950 3075)(-3300 3075);
WIRE 16 -1 (-3009 2575)(-2950 2575);
WIRE 16 -1 (-2000 2225)(-2000 2075);
WIRE 16 -1 (-25 2408)(-25 2550);
WIRE 16 -1 (-555 2558)(-555 2408);
WIRE 16 -1 (-3500 3775)(-3500 3950);
WIRE 16 -1 (-3500 3950)(-3050 3950);
WIRE 16 -1 (-3050 3950)(-3050 3525);
WIRE 16 -1 (-3050 3525)(-3030 3525);
WIRE 16 -1 (-3030 3525)(-2950 3525);
WIRE 16 -1 (-3030 3475)(-3030 3525);
WIRE 16 -1 (-2950 3475)(-3030 3475);
WIRE 16 -1 (-2950 3425)(-3030 3425);
WIRE 16 -1 (-3030 3425)(-3030 3475);
WIRE 16 -1 (-3030 3375)(-3030 3425);
WIRE 16 -1 (-2950 3375)(-3030 3375);
WIRE 16 -1 (-3030 3325)(-3030 3375);
WIRE 16 -1 (-2950 3325)(-3030 3325);
WIRE 16 -1 (-25 3258)(-25 3175);
WIRE 16 -1 (-75 3258)(-25 3258);
WIRE 16 -1 (-555 3258)(-75 3258);
WIRE 16 -1 (-555 3183)(-555 3258);
WIRE 16 -1 (-950 3250)(-950 3375);
WIRE 16 -1 (-950 3375)(-950 3500);
WIRE 16 -1 (-1500 3250)(-1500 3375);
WIRE 16 -1 (-1500 3375)(-950 3375);
WIRE 16 -1 (-2150 3375)(-1843 3375);
WIRE 16 -1 (-1843 3375)(-1500 3375);
WIRE 16 -1 (-2150 3325)(-1843 3325);
WIRE 16 -1 (-1843 3325)(-1843 3375);
WIRE 16 -1 (-2150 3275)(-1843 3275);
WIRE 16 -1 (-1843 3275)(-1843 3325);
WIRE 16 -1 (-2150 3225)(-1843 3225);
WIRE 16 -1 (-1843 3225)(-1843 3275);
WIRE 16 -1 (-1843 3175)(-2150 3175);
WIRE 16 -1 (-1843 3175)(-1843 3225);
WIRE 16 -1 (-2150 3125)(-1843 3125);
WIRE 16 -1 (-1843 3125)(-1843 3175);
WIRE 16 -1 (-2150 3075)(-1843 3075);
WIRE 16 -1 (-1843 3075)(-1843 3125);
WIRE 16 -1 (-1843 3025)(-1843 3075);
WIRE 16 -1 (-2150 3025)(-1843 3025);
WIRE 16 -1 (-2950 2775)(-3750 2775);
FORCEPROP 2 LAST SIG_NAME P12V_OCP_ISET_2
J 0
(-3435 2785);
DISPLAY 0.574468 (-3435 2785);
WIRE 16 -1 (-3750 2675)(-3750 2775);
WIRE 16 -1 (-2050 3625)(-2050 3525);
FORCEPROP 2 LAST SIG_NAME HP_LVC3_OCP_V3_2_P12V_PWRGD
J 0
(-1985 3535);
DISPLAY 0.574468 (-1985 3535);
WIRE 16 -1 (-2050 3525)(-1300 3525);
WIRE 16 -1 (-2150 3525)(-2050 3525);
WIRE 16 -1 (125 6475)(-1100 6475);
FORCEPROP 2 LAST SIG_NAME HP_LVC3_OCP_V3_2_EN
J 0
(-1010 6485);
DISPLAY 0.808511 (-1010 6485);
WIRE 16 -1 (-2150 2575)(-2000 2575);
FORCEPROP 2 LAST SIG_NAME P12V_OCP_IMON_2
J 0
(-2055 2583);
DISPLAY 0.574468 (-2055 2583);
WIRE 16 -1 (-2000 2425)(-2000 2575);
WIRE 16 -1 (-1550 2425)(-1550 2575);
WIRE 16 -1 (-2000 2575)(-1550 2575);
WIRE 16 -1 (-1550 2575)(-950 2575);
WIRE 16 -1 (-950 2575)(-950 2200);
WIRE 16 -1 (-600 2200)(-950 2200);
WIRE 16 -1 (-600 2200)(-250 2200);
WIRE 16 -1 (-600 2200)(-600 2075);
WIRE 16 -1 (-600 2075)(-250 2075);
WIRE 16 2175 (-525 2300)(200 2300);
WIRE 16 2175 (200 2300)(200 2000);
WIRE 16 2175 (-525 2300)(-525 2000);
WIRE 16 2175 (-525 2000)(200 2000);
WIRE 16 -1 (-50 2075)(1050 2075);
FORCEPROP 2 LAST SIG_NAME P12V_OCP_V3_2_ISENSE_MPS_TIC
J 0
(240 2085);
DISPLAY 0.574468 (240 2085);
WIRE 16 -1 (-50 2200)(1050 2200);
FORCEPROP 2 LAST SIG_NAME P12V_OCP_V3_2_ISENSE_MPS_MAM
J 0
(240 2210);
DISPLAY 0.574468 (240 2210);
WIRE 16 -1 (-2150 2925)(-1500 2925);
FORCEPROP 2 LAST SIG_NAME P12V_OCP_AVIN_PD_2
J 0
(-2060 2935);
DISPLAY 0.574468 (-2060 2935);
WIRE 16 -1 (-1400 2925)(-1500 2925);
WIRE 16 -1 (-1500 3050)(-1500 2925);
WIRE 16 -1 (-2150 2825)(-950 2825);
FORCEPROP 2 LAST SIG_NAME P12V_OCP_OV_FB_2
J 0
(-2060 2835);
DISPLAY 0.574468 (-2060 2835);
WIRE 16 -1 (-950 3050)(-950 2825);
WIRE 16 -1 (-555 2825)(-950 2825);
WIRE 16 -1 (-555 2825)(-555 2758);
WIRE 16 -1 (-555 2983)(-555 2825);
WIRE 16 -1 (-25 2825)(-25 2975);
WIRE 16 -1 (850 2825)(-25 2825);
FORCEPROP 2 LAST SIG_NAME P12V_OCP_AVIN_PD_2
J 0
(365 2835);
DISPLAY 0.574468 (365 2835);
WIRE 16 -1 (-25 2750)(-25 2825);
WIRE 16 3135 (-1955 4733)(-1955 4133);
WIRE 16 3135 (-2730 4308)(-1530 4308);
WIRE 16 3135 (-2380 4733)(-2380 4133);
WIRE 16 -1 (-1525 2675)(-2150 2675);
FORCEPROP 2 LAST SIG_NAME P12V_OCP_FLTB_2
J 0
(-2060 2685);
DISPLAY 0.574468 (-2060 2685);
WIRE 16 -1 (-2950 3175)(-3975 3175);
FORCEPROP 2 LAST SIG_NAME P12V_OCP_V3_2_EN_2_R3
J 0
(-3630 3175);
DISPLAY 0.574468 (-3630 3175);
WIRE 16 -1 (-2950 2675)(-3330 2675);
FORCEPROP 2 LAST SIG_NAME P12V_OCP_SS_2
J 0
(-3385 2685);
DISPLAY 0.574468 (-3385 2685);
WIRE 16 -1 (-3330 2608)(-3330 2675);
WIRE 16 -1 (-4175 2875)(-4175 2825);
WIRE 16 -1 (-2950 2875)(-4175 2875);
FORCEPROP 2 LAST SIG_NAME P12V_OCP_TIMER_2
J 0
(-3460 2885);
DISPLAY 0.574468 (-3460 2885);
WIRE 16 -1 (-4175 3175)(-4850 3175);
FORCEPROP 2 LAST SIG_NAME HP_LVC3_OCP_V3_2_EN
J 0
(-4785 3185);
DISPLAY 0.638298 (-4785 3185);
WIRE 16 -1 (150 6275)(150 6375);
WIRE 16 -1 (1275 6375)(150 6375);
FORCEPROP 2 LAST SIG_NAME P3V3_OCP_MODE_2
J 0
(765 6385);
DISPLAY 0.574468 (765 6385);
WIRE 16 -1 (-250 6375)(150 6375);
WIRE 16 -1 (-250 6275)(-250 6375);
WIRE 16 -1 (1275 6475)(325 6475);
FORCEPROP 2 LAST SIG_NAME P3V3_OCP_EN_2
J 0
(815 6485);
DISPLAY 0.574468 (815 6485);
WIRE 16 -1 (495 6258)(495 6325);
WIRE 16 -1 (495 6325)(1275 6325);
FORCEPROP 2 LAST SIG_NAME P3V3_OCP_ILIMIT_2
J 0
(765 6335);
DISPLAY 0.510638 (765 6335);
WIRE 16 -1 (870 6208)(870 6275);
FORCEPROP 2 LAST SIG_NAME P3V3_OCP_DVDT_2
J 0
(765 6285);
DISPLAY 0.574468 (765 6285);
WIRE 16 -1 (870 6275)(1275 6275);
WIRE 16 -1 (2075 6375)(2500 6375);
FORCEPROP 2 LAST SIG_NAME P3V3_OCP_GATE_PU207_2
J 0
(2156 6400);
DISPLAY 0.574468 (2156 6400);
WIRE 16 -1 (2500 6375)(2500 6250);
WIRE 16 2175 (-5500 7600)(-3797 7600);
WIRE 16 2175 (-3797 7600)(-3797 6700);
WIRE 16 2175 (-5500 7600)(-5500 6700);
WIRE 16 2175 (-5500 6700)(-3797 6700);
DOT 1 (-250 5958);
DOT 1 (470 6958);
DOT 1 (2500 5975);
DOT 1 (2900 6575);
DOT 1 (150 6375);
DOT 1 (-3300 2975);
DOT 1 (-3500 3950);
DOT 1 (-3030 3375);
DOT 1 (-3030 3425);
DOT 1 (-3030 3475);
DOT 1 (-3030 3525);
DOT 1 (-2000 2575);
DOT 1 (-1550 2075);
DOT 1 (-1550 2575);
DOT 1 (-1500 2925);
DOT 1 (-1843 3125);
DOT 1 (-1843 3075);
DOT 1 (-1843 3175);
DOT 1 (-1843 3275);
DOT 1 (-1843 3325);
DOT 1 (-1843 3375);
DOT 1 (-2050 3525);
DOT 1 (-1500 3375);
DOT 1 (-950 2825);
DOT 1 (-600 2200);
DOT 1 (-355 2408);
DOT 1 (-555 2825);
DOT 1 (-950 3375);
DOT 1 (-25 2825);
DOT 1 (-75 3258);
DOT 1 (475 3500);
DOT 1 (-1843 3225);
FORCENOTE
POP
(-2330 4233) 0;
DISPLAY LEFT (-2330 4233);
DISPLAY 1.021277 (-2330 4233);
FORCENOTE
PR3853
(-2680 4333) 0;
DISPLAY LEFT (-2680 4333);
DISPLAY 1.021277 (-2680 4333);
FORCENOTE
MP5025A/
(-1905 4683) 0;
DISPLAY LEFT (-1905 4683);
DISPLAY 1.021277 (-1905 4683);
FORCENOTE
MP5022A
(-1905 4633) 0;
DISPLAY LEFT (-1905 4633);
DISPLAY 1.021277 (-1905 4633);
FORCENOTE
DE-POP
(-1905 4333) 0;
DISPLAY LEFT (-1905 4333);
DISPLAY 1.021277 (-1905 4333);
FORCENOTE
DE-POP
(-1905 4233) 0;
DISPLAY LEFT (-1905 4233);
DISPLAY 1.021277 (-1905 4233);
FORCENOTE
DE-POP
(-1905 4133) 0;
DISPLAY LEFT (-1905 4133);
DISPLAY 1.021277 (-1905 4133);
FORCENOTE
POP
(-2330 4133) 0;
DISPLAY LEFT (-2330 4133);
DISPLAY 1.021277 (-2330 4133);
FORCENOTE
PR3857
(-2680 4233) 0;
DISPLAY LEFT (-2680 4233);
DISPLAY 1.021277 (-2680 4233);
FORCENOTE
OCP=IMAX*1.3=1.43A
(-5425 7250) 0;
DISPLAY LEFT (-5425 7250);
DISPLAY 0.936170 (-5425 7250);
FORCENOTE
IMAX=1.1A
(-5425 7325) 0;
DISPLAY LEFT (-5425 7325);
DISPLAY 0.936170 (-5425 7325);
FORCENOTE
P3V3_OCP_V3_2_R
(-5425 7400) 0;
DISPLAY LEFT (-5425 7400);
DISPLAY 0.936170 (-5425 7400);
FORCENOTE
P12V_OCP_V3_2
(-5425 7000) 0;
DISPLAY LEFT (-5425 7000);
DISPLAY 1.021277 (-5425 7000);
FORCENOTE
OCP=IMAX*1.3=8.58A
(-5425 6850) 0;
DISPLAY LEFT (-5425 6850);
DISPLAY 1.021277 (-5425 6850);
FORCENOTE
IMAX=6.6A
(-5425 6925) 0;
DISPLAY LEFT (-5425 6925);
DISPLAY 1.021277 (-5425 6925);
FORCENOTE
DESIGN SPECIFICATION
(-5416 7494) 0;
DISPLAY LEFT (-5416 7494);
DISPLAY 1.170213 (-5416 7494);
FORCENOTE
=1.6A
(250 5650) 0;
DISPLAY LEFT (250 5650);
DISPLAY 1.021277 (250 5650);
PAINT WHITE (250 5650);
FORCENOTE
CURRENT LIMIT
(250 5716) 0;
DISPLAY LEFT (250 5716);
DISPLAY 1.021277 (250 5716);
PAINT WHITE (250 5716);
FORCENOTE
20211108 MODIFY FOR GT
(-3250 7425) 0;
DISPLAY LEFT (-3250 7425);
DISPLAY 2.510638 (-3250 7425);
PAINT PINK (-3250 7425);
FORCENOTE
TDELAY: 6.29MS
(-4850 2175) 0;
DISPLAY LEFT (-4850 2175);
DISPLAY 1.021277 (-4850 2175);
PAINT WHITE (-4850 2175);
FORCENOTE
START UP TIME:8.62MS
(-3750 2125) 0;
DISPLAY LEFT (-3750 2125);
DISPLAY 1.021277 (-3750 2125);
PAINT WHITE (-3750 2125);
FORCENOTE
VIMON(MAX)= 1.582V @ IOUT=9.09A
(-3325 1875) 0;
DISPLAY LEFT (-3325 1875);
DISPLAY 1.021277 (-3325 1875);
PAINT WHITE (-3325 1875);
FORCENOTE
PR3850
(-2675 4525) 0;
DISPLAY LEFT (-2675 4525);
DISPLAY 1.021277 (-2675 4525);
FORCENOTE
PR3852
(-2680 4433) 0;
DISPLAY LEFT (-2680 4433);
DISPLAY 1.021277 (-2680 4433);
FORCENOTE
PC1320
(-2680 4133) 0;
DISPLAY LEFT (-2680 4133);
DISPLAY 1.021277 (-2680 4133);
FORCENOTE
POP
(-2330 4333) 0;
DISPLAY LEFT (-2330 4333);
DISPLAY 1.021277 (-2330 4333);
FORCENOTE
MP5022C
(-2355 4633) 0;
DISPLAY LEFT (-2355 4633);
DISPLAY 1.021277 (-2355 4633);
FORCENOTE
DE-POP
(-2330 4433) 0;
DISPLAY LEFT (-2330 4433);
DISPLAY 1.021277 (-2330 4433);
FORCENOTE
MP5025C/
(-2355 4683) 0;
DISPLAY LEFT (-2355 4683);
DISPLAY 1.021277 (-2355 4683);
FORCENOTE
DE-POP
(-2330 4533) 0;
DISPLAY LEFT (-2330 4533);
DISPLAY 1.021277 (-2330 4533);
FORCENOTE
PU206 OPTIONAL BOM
(-2730 4783) 0;
DISPLAY LEFT (-2730 4783);
DISPLAY 1.021277 (-2730 4783);
FORCENOTE
POP
(-1855 4433) 0;
DISPLAY LEFT (-1855 4433);
DISPLAY 1.021277 (-1855 4433);
FORCENOTE
POP
(-1855 4533) 0;
DISPLAY LEFT (-1855 4533);
DISPLAY 1.021277 (-1855 4533);
FORCENOTE
START UP TIME:4.7MS
(1200 5675) 0;
DISPLAY LEFT (1200 5675);
DISPLAY 1.021277 (1200 5675);
PAINT WHITE (1200 5675);
FORCENOTE
TFAULT: 1.27MS
(-4850 2250) 0;
DISPLAY LEFT (-4850 2250);
DISPLAY 1.021277 (-4850 2250);
PAINT WHITE (-4850 2250);
FORCENOTE
VTH>1.391V(HIGH)
(-5275 2934) 0;
DISPLAY LEFT (-5275 2934);
DISPLAY 1.021277 (-5275 2934);
PAINT WHITE (-5275 2934);
FORCENOTE
ENABLE:
(-5275 3000) 0;
DISPLAY LEFT (-5275 3000);
DISPLAY 1.021277 (-5275 3000);
PAINT WHITE (-5275 3000);
QUIT
